FILE_TYPE = MACRO_DRAWING;
SET COLOR_WIRE YELLOW;
SET COLOR_PROP MONO;
SET COLOR_DOT WHITE;
SET COLOR_ARC YELLOW;
SET COLOR_BODY GREEN;
SET COLOR_NOTE MONO;
SET PROP_DISPLAY VALUE;
SET PAGE_NUMBER P200;
FORCEADD TTL1G126_A..1
(-2900 2225);
FORCEPROP 1 LASTPIN (-3050 2225) $PN 2
J 2
(-3025 2235);
DISPLAY 0.617021 (-3025 2235);
PAINT WHITE (-3025 2235);
FORCEPROP 1 LAST MATERIAL IC
J 0
(-2950 2375);
DISPLAY 0.617021 (-2950 2375);
PAINT SKYBLUE (-2950 2375);
FORCEPROP 1 LASTPIN (-2900 2125) $PN 1
J 0
(-2895 2075);
DISPLAY 0.617021 (-2895 2075);
PAINT WHITE (-2895 2075);
FORCEPROP 1 LASTPIN (-2750 2225) $PN 4
J 0
(-2785 2235);
DISPLAY 0.617021 (-2785 2235);
PAINT WHITE (-2785 2235);
FORCEPROP 1 LAST LOCATION U1D1
J 0
(-2950 2425);
DISPLAY 0.617021 (-2950 2425);
PAINT AQUA (-2950 2425);
FORCEPROP 1 LAST POWER_GROUP GND=GND
J 0
(-3225 2085);
DISPLAY 0.617021 (-3225 2085);
PAINT ORANGE (-3225 2085);
FORCEPROP 1 LAST POWER_GROUP VCC=P3V3_STBY
J 0
(-3250 2050);
DISPLAY 0.617021 (-3250 2050);
PAINT ORANGE (-3250 2050);
FORCEPROP 1 LAST VALUE 74HC1G126
J 0
(-2950 2325);
DISPLAY 0.617021 (-2950 2325);
PAINT SKYBLUE (-2950 2325);
FORCEPROP 1 LAST PART_NUMBER A79322-001
J 0
(-3275 2135);
DISPLAY 0.617021 (-3275 2135);
PAINT BLUE (-3275 2135);
FORCEPROP 2 LAST SEC 1
J 0
(-2950 2575);
DISPLAY 0.680851 (-2950 2575);
PAINT MONO (-2950 2575);
DISPLAY INVISIBLE (-2950 2575);
FORCEPROP 2 LAST SEC_TYPE SOT
J 0
(-2950 2575);
DISPLAY 1.021277 (-2950 2575);
PAINT ORANGE (-2950 2575);
DISPLAY INVISIBLE (-2950 2575);
FORCEPROP 2 LAST ROOM HOT_SWAP
J 0
(-2950 2475);
PAINT MONO (-2950 2475);
DISPLAY INVISIBLE (-2950 2475);
FORCEPROP 1 LAST PATH I103
J 2
(-3005 2325);
DISPLAY 0.978723 (-3005 2325);
PAINT GREEN (-3005 2325);
DISPLAY INVISIBLE (-3005 2325);
FORCEPROP 2 LAST CDS_LOCATION U1D1
J 0
(-2950 2425);
DISPLAY 0.617021 (-2950 2425);
PAINT AQUA (-2950 2425);
DISPLAY INVISIBLE (-2950 2425);
FORCEPROP 1 LAST PACK_TYPE SOT
J 0
(-2950 2475);
DISPLAY 0.978723 (-2950 2475);
PAINT SKYBLUE (-2950 2475);
DISPLAY INVISIBLE (-2950 2475);
FORCEPROP 2 LAST CDS_LIB mstr_ttl
J 0
(-2900 2225);
PAINT ORANGE (-2900 2225);
DISPLAY INVISIBLE (-2900 2225);
FORCEADD AGND0..1
(-1650 -350);
FORCEPROP 3 LASTPIN (-1650 -300) SIG_NAME AGND_HSC\g
J 0
(-1640 -290);
DISPLAY 0.659574 (-1640 -290);
PAINT MONO (-1640 -290);
DISPLAY INVISIBLE (-1640 -290);
FORCEPROP 1 LAST HDL_POWER AGND_HSC
J 1
(-1650 -400);
DISPLAY 0.617021 (-1650 -400);
PAINT GREEN (-1650 -400);
FORCEPROP 2 LAST ROOM VR_P3V3
J 0
(-1675 -375);
PAINT ORANGE (-1675 -375);
DISPLAY INVISIBLE (-1675 -375);
FORCEPROP 1 LAST PATH I106
J 0
(-1575 -350);
DISPLAY 0.872340 (-1575 -350);
PAINT AQUA (-1575 -350);
DISPLAY INVISIBLE (-1575 -350);
FORCEPROP 2 LAST BOM_COST MIO_VRD_MAIN
J 0
(-1625 -375);
PAINT ORANGE (-1625 -375);
DISPLAY INVISIBLE (-1625 -375);
FORCEPROP 2 LAST CDS_LIB mstr_symbols
J 0
(-1650 -350);
PAINT ORANGE (-1650 -350);
DISPLAY INVISIBLE (-1650 -350);
FORCEPROP 1 LAST VOLTAGE 0
J 0
(-1650 -350);
PAINT SKYBLUE (-1650 -350);
DISPLAY INVISIBLE (-1650 -350);
FORCEPROP 1 LAST BODY_TYPE PLUMBING
J 0
(-1695 -393);
DISPLAY 0.340426 (-1695 -393);
PAINT GREEN (-1695 -393);
DISPLAY INVISIBLE (-1695 -393);
FORCEADD RES..2
(-1650 -150);
FORCEPROP 1 LAST MATERIAL CHIP
J 0
(-1610 -225);
DISPLAY 0.617021 (-1610 -225);
PAINT SKYBLUE (-1610 -225);
FORCEPROP 1 LAST TOLERANCE 1%
J 0
(-1605 -125);
DISPLAY 0.617021 (-1605 -125);
PAINT SKYBLUE (-1605 -125);
FORCEPROP 1 LAST WATTAGE 1/16W
J 0
(-1610 -175);
DISPLAY 0.617021 (-1610 -175);
PAINT SKYBLUE (-1610 -175);
FORCEPROP 1 LASTPIN (-1650 -250) $PN 2
J 0
(-1645 -240);
DISPLAY 0.617021 (-1645 -240);
PAINT ORANGE (-1645 -240);
FORCEPROP 1 LAST LOCATION R9P11
J 0
(-1605 -25);
DISPLAY 0.617021 (-1605 -25);
PAINT AQUA (-1605 -25);
FORCEPROP 1 LAST VALUE 10.0K
J 0
(-1605 -75);
DISPLAY 0.617021 (-1605 -75);
PAINT SKYBLUE (-1605 -75);
FORCEPROP 1 LASTPIN (-1650 -50) $PN 1
J 0
(-1645 -88);
DISPLAY 0.617021 (-1645 -88);
PAINT ORANGE (-1645 -88);
FORCEPROP 0 LAST CONFIG 64.1002D.6DL
J 0
(-1600 -375);
DISPLAY 0.638298 (-1600 -375);
PAINT BROWN (-1600 -375);
DISPLAY BOTH (-1600 -375);
FORCEPROP 1 LAST PACK_TYPE 0402
J 0
(-1610 -325);
DISPLAY 0.617021 (-1610 -325);
PAINT SKYBLUE (-1610 -325);
FORCEPROP 1 LAST PART_NUMBER G21796-016
J 0
(-1610 -275);
DISPLAY 0.617021 (-1610 -275);
PAINT BLUE (-1610 -275);
FORCEPROP 2 LAST CDS_LIB mstr_discrete
J 0
(-1650 -150);
PAINT ORANGE (-1650 -150);
DISPLAY INVISIBLE (-1650 -150);
FORCEPROP 2 LAST CDS_LOCATION R9P11
J 0
(-1605 -25);
DISPLAY 0.617021 (-1605 -25);
PAINT AQUA (-1605 -25);
DISPLAY INVISIBLE (-1605 -25);
FORCEPROP 2 LAST SEC_TYPE 0402
J 0
(-1600 75);
DISPLAY 1.021277 (-1600 75);
PAINT ORANGE (-1600 75);
DISPLAY INVISIBLE (-1600 75);
FORCEPROP 2 LAST SEC 1
J 0
(-1600 75);
DISPLAY 0.680851 (-1600 75);
PAINT MONO (-1600 75);
DISPLAY INVISIBLE (-1600 75);
FORCEPROP 1 LAST PATH I108
J 0
(-1600 25);
DISPLAY 0.978723 (-1600 25);
PAINT WHITE (-1600 25);
DISPLAY INVISIBLE (-1600 25);
FORCEPROP 2 LAST ROOM HOT_SWAP
J 0
(-1600 25);
PAINT MONO (-1600 25);
DISPLAY INVISIBLE (-1600 25);
FORCEADD P12V_STBY..1
(-1650 525);
FORCEPROP 3 LASTPIN (-1650 475) SIG_NAME P12V_STBY\g
J 0
(-1640 485);
DISPLAY 0.659574 (-1640 485);
PAINT MONO (-1640 485);
DISPLAY INVISIBLE (-1640 485);
FORCEPROP 2 LAST CDS_LIB mstr_symbols
J 0
(-1650 525);
PAINT ORANGE (-1650 525);
DISPLAY INVISIBLE (-1650 525);
FORCEPROP 1 LAST PATH I109
J 0
(-1605 527);
DISPLAY 0.340426 (-1605 527);
PAINT GREEN (-1605 527);
DISPLAY INVISIBLE (-1605 527);
FORCEPROP 1 LAST SIZE 1B
J 0
(-1605 547);
DISPLAY 0.340426 (-1605 547);
PAINT GREEN (-1605 547);
DISPLAY INVISIBLE (-1605 547);
FORCEPROP 1 LAST VOLTAGE 12.0V
J 0
(-1695 482);
DISPLAY 0.340426 (-1695 482);
PAINT SKYBLUE (-1695 482);
DISPLAY INVISIBLE (-1695 482);
FORCEPROP 1 LAST BODY_TYPE PLUMBING
J 0
(-1695 482);
DISPLAY 0.340426 (-1695 482);
PAINT GREEN (-1695 482);
DISPLAY INVISIBLE (-1695 482);
FORCEPROP 1 LAST HDL_POWER P12V_STBY
J 0
(-1950 400);
DISPLAY 0.872340 (-1950 400);
PAINT ORANGE (-1950 400);
DISPLAY INVISIBLE (-1950 400);
FORCEADD GND..1
(-3075 -475);
FORCEPROP 3 LASTPIN (-3075 -425) SIG_NAME GND\g
J 0
(-3065 -415);
DISPLAY 0.659574 (-3065 -415);
PAINT MONO (-3065 -415);
DISPLAY INVISIBLE (-3065 -415);
FORCEPROP 1 LAST VOLTAGE 0.0V
J 0
(-3120 -518);
DISPLAY 0.340426 (-3120 -518);
PAINT SKYBLUE (-3120 -518);
DISPLAY INVISIBLE (-3120 -518);
FORCEPROP 2 LAST CDS_LIB mstr_symbols
J 0
(-3075 -475);
PAINT ORANGE (-3075 -475);
DISPLAY INVISIBLE (-3075 -475);
FORCEPROP 1 LAST PATH I114
J 0
(-3000 -475);
DISPLAY 0.872340 (-3000 -475);
PAINT AQUA (-3000 -475);
DISPLAY INVISIBLE (-3000 -475);
FORCEPROP 1 LAST SIZE 1B
J 0
(-3000 -525);
DISPLAY 0.872340 (-3000 -525);
PAINT AQUA (-3000 -525);
DISPLAY INVISIBLE (-3000 -525);
FORCEPROP 1 LAST BODY_TYPE PLUMBING
J 0
(-3120 -518);
DISPLAY 0.340426 (-3120 -518);
PAINT GREEN (-3120 -518);
DISPLAY INVISIBLE (-3120 -518);
FORCEPROP 1 LAST HDL_POWER GND
J 0
(-3075 -325);
DISPLAY 0.872340 (-3075 -325);
PAINT GREEN (-3075 -325);
DISPLAY INVISIBLE (-3075 -325);
FORCEADD OFFPAGE..2
(-975 2225);
FORCEPROP 2 LAST $XR0 170 
J 0
(-786 2225);
DISPLAY 0.638298 (-786 2225);
PAINT MONO (-786 2225);
FORCEPROP 2 LAST PATH I118
J 0
(-800 2300);
DISPLAY 1.021277 (-800 2300);
PAINT ORANGE (-800 2300);
DISPLAY INVISIBLE (-800 2300);
FORCEPROP 2 LAST CDS_LIB mstr_standard
J 0
(-975 2225);
PAINT ORANGE (-975 2225);
DISPLAY INVISIBLE (-975 2225);
FORCEPROP 1 LAST OFFPAGE TRUE
J 0
(-650 2100);
DISPLAY 0.872340 (-650 2100);
PAINT GREEN (-650 2100);
DISPLAY INVISIBLE (-650 2100);
FORCEPROP 1 LAST COMMENT_BODY TRUE
J 0
(-1020 2130);
DISPLAY 0.872340 (-1020 2130);
PAINT GREEN (-1020 2130);
DISPLAY INVISIBLE (-1020 2130);
FORCEADD OFFPAGE..2
(2575 -50);
FORCEPROP 2 LAST $XR2 170 
J 0
(2764 -86);
DISPLAY 0.638298 (2764 -86);
PAINT MONO (2764 -86);
FORCEPROP 2 LAST $XR1 145 
J 0
(2884 -50);
DISPLAY 0.638298 (2884 -50);
PAINT MONO (2884 -50);
FORCEPROP 2 LAST $XR0 120 
J 0
(2764 -50);
DISPLAY 0.638298 (2764 -50);
PAINT MONO (2764 -50);
FORCEPROP 2 LAST CDS_LIB mstr_standard
J 0
(2575 -50);
PAINT ORANGE (2575 -50);
DISPLAY INVISIBLE (2575 -50);
FORCEPROP 2 LAST PATH I121
J 0
(2750 25);
DISPLAY 1.021277 (2750 25);
PAINT ORANGE (2750 25);
DISPLAY INVISIBLE (2750 25);
FORCEPROP 1 LAST OFFPAGE TRUE
J 0
(2900 -175);
DISPLAY 0.872340 (2900 -175);
PAINT GREEN (2900 -175);
DISPLAY INVISIBLE (2900 -175);
FORCEPROP 1 LAST COMMENT_BODY TRUE
J 0
(2530 -145);
DISPLAY 0.872340 (2530 -145);
PAINT GREEN (2530 -145);
DISPLAY INVISIBLE (2530 -145);
FORCEADD OFFPAGE..2
(2550 675);
FORCEPROP 2 LAST $XR0 161 
J 0
(2739 675);
DISPLAY 0.638298 (2739 675);
PAINT MONO (2739 675);
FORCEPROP 2 LAST CDS_LIB mstr_standard
J 0
(2550 675);
PAINT ORANGE (2550 675);
DISPLAY INVISIBLE (2550 675);
FORCEPROP 2 LAST PATH I134
J 0
(2725 750);
DISPLAY 1.021277 (2725 750);
PAINT ORANGE (2725 750);
DISPLAY INVISIBLE (2725 750);
FORCEPROP 1 LAST OFFPAGE TRUE
J 0
(2875 550);
DISPLAY 0.872340 (2875 550);
PAINT GREEN (2875 550);
DISPLAY INVISIBLE (2875 550);
FORCEPROP 1 LAST COMMENT_BODY TRUE
J 0
(2505 580);
DISPLAY 0.872340 (2505 580);
PAINT GREEN (2505 580);
DISPLAY INVISIBLE (2505 580);
FORCEADD OFFPAGE..2
(2525 900);
FORCEPROP 2 LAST $XR0 191 
J 0
(2714 900);
DISPLAY 0.638298 (2714 900);
PAINT MONO (2714 900);
FORCEPROP 2 LAST CDS_LIB mstr_standard
J 0
(2525 900);
PAINT ORANGE (2525 900);
DISPLAY INVISIBLE (2525 900);
FORCEPROP 2 LAST PATH I135
J 0
(2700 975);
DISPLAY 1.021277 (2700 975);
PAINT ORANGE (2700 975);
DISPLAY INVISIBLE (2700 975);
FORCEPROP 1 LAST OFFPAGE TRUE
J 0
(2850 775);
DISPLAY 0.872340 (2850 775);
PAINT GREEN (2850 775);
DISPLAY INVISIBLE (2850 775);
FORCEPROP 1 LAST COMMENT_BODY TRUE
J 0
(2480 805);
DISPLAY 0.872340 (2480 805);
PAINT GREEN (2480 805);
DISPLAY INVISIBLE (2480 805);
FORCEADD P12V_STBY..1
(-1975 1075);
FORCEPROP 3 LASTPIN (-1975 1025) SIG_NAME P12V_STBY\g
J 0
(-1965 1035);
DISPLAY 0.659574 (-1965 1035);
PAINT MONO (-1965 1035);
DISPLAY INVISIBLE (-1965 1035);
FORCEPROP 1 LAST PATH I144
J 0
(-1930 1077);
DISPLAY 0.340426 (-1930 1077);
PAINT GREEN (-1930 1077);
DISPLAY INVISIBLE (-1930 1077);
FORCEPROP 2 LAST CDS_LIB mstr_symbols
J 0
(-1975 1075);
PAINT ORANGE (-1975 1075);
DISPLAY INVISIBLE (-1975 1075);
FORCEPROP 1 LAST SIZE 1B
J 0
(-1930 1097);
DISPLAY 0.340426 (-1930 1097);
PAINT GREEN (-1930 1097);
DISPLAY INVISIBLE (-1930 1097);
FORCEPROP 1 LAST VOLTAGE 12.0V
J 0
(-2020 1032);
DISPLAY 0.340426 (-2020 1032);
PAINT SKYBLUE (-2020 1032);
DISPLAY INVISIBLE (-2020 1032);
FORCEPROP 1 LAST BODY_TYPE PLUMBING
J 0
(-2020 1032);
DISPLAY 0.340426 (-2020 1032);
PAINT GREEN (-2020 1032);
DISPLAY INVISIBLE (-2020 1032);
FORCEPROP 1 LAST HDL_POWER P12V_STBY
J 0
(-2275 950);
DISPLAY 0.872340 (-2275 950);
PAINT ORANGE (-2275 950);
DISPLAY INVISIBLE (-2275 950);
FORCEADD AGND0..1
(-1975 175);
FORCEPROP 3 LASTPIN (-1975 225) SIG_NAME AGND_HSC\g
J 0
(-1965 235);
DISPLAY 0.659574 (-1965 235);
PAINT MONO (-1965 235);
DISPLAY INVISIBLE (-1965 235);
FORCEPROP 1 LAST HDL_POWER AGND_HSC
J 1
(-1975 125);
DISPLAY 0.617021 (-1975 125);
PAINT GREEN (-1975 125);
FORCEPROP 1 LAST VOLTAGE 0
J 0
(-1975 175);
PAINT SKYBLUE (-1975 175);
DISPLAY INVISIBLE (-1975 175);
FORCEPROP 2 LAST CDS_LIB mstr_symbols
J 0
(-1975 175);
PAINT ORANGE (-1975 175);
DISPLAY INVISIBLE (-1975 175);
FORCEPROP 1 LAST PATH I147
J 0
(-1900 175);
DISPLAY 0.872340 (-1900 175);
PAINT AQUA (-1900 175);
DISPLAY INVISIBLE (-1900 175);
FORCEPROP 2 LAST BOM_COST MIO_VRD_MAIN
J 0
(-1950 150);
PAINT ORANGE (-1950 150);
DISPLAY INVISIBLE (-1950 150);
FORCEPROP 2 LAST ROOM VR_P3V3
J 0
(-2000 150);
PAINT ORANGE (-2000 150);
DISPLAY INVISIBLE (-2000 150);
FORCEPROP 1 LAST BODY_TYPE PLUMBING
J 0
(-2020 132);
DISPLAY 0.340426 (-2020 132);
PAINT GREEN (-2020 132);
DISPLAY INVISIBLE (-2020 132);
FORCEADD RES..2
(600 1100);
FORCEPROP 1 LASTPIN (600 1000) $PN 2
J 0
(605 1010);
DISPLAY 0.617021 (605 1010);
PAINT ORANGE (605 1010);
FORCEPROP 1 LASTPIN (600 1200) $PN 1
J 0
(605 1162);
DISPLAY 0.617021 (605 1162);
PAINT ORANGE (605 1162);
FORCEPROP 1 LAST TOLERANCE 1%
J 0
(645 1125);
DISPLAY 0.617021 (645 1125);
PAINT SKYBLUE (645 1125);
FORCEPROP 1 LAST WATTAGE 1/16W
J 0
(640 1075);
DISPLAY 0.617021 (640 1075);
PAINT SKYBLUE (640 1075);
FORCEPROP 1 LAST LOCATION R9P6
J 0
(645 1225);
DISPLAY 0.617021 (645 1225);
PAINT AQUA (645 1225);
FORCEPROP 1 LAST VALUE 10.0K
J 0
(645 1175);
DISPLAY 0.617021 (645 1175);
PAINT SKYBLUE (645 1175);
FORCEPROP 1 LAST MATERIAL CHIP
J 0
(640 1025);
DISPLAY 0.617021 (640 1025);
PAINT SKYBLUE (640 1025);
FORCEPROP 1 LAST PART_NUMBER G21796-016
J 0
(640 975);
DISPLAY 0.617021 (640 975);
PAINT BLUE (640 975);
FORCEPROP 1 LAST PACK_TYPE 0402
J 0
(640 925);
DISPLAY 0.617021 (640 925);
PAINT SKYBLUE (640 925);
FORCEPROP 2 LAST CDS_LIB mstr_discrete
J 0
(600 1100);
PAINT ORANGE (600 1100);
DISPLAY INVISIBLE (600 1100);
FORCEPROP 2 LAST CDS_LOCATION R9P6
J 0
(645 1225);
DISPLAY 0.617021 (645 1225);
PAINT AQUA (645 1225);
DISPLAY INVISIBLE (645 1225);
FORCEPROP 2 LAST ROOM HOT_SWAP
J 0
(650 1275);
PAINT MONO (650 1275);
DISPLAY INVISIBLE (650 1275);
FORCEPROP 1 LAST PATH I149
J 0
(650 1275);
DISPLAY 0.978723 (650 1275);
PAINT WHITE (650 1275);
DISPLAY INVISIBLE (650 1275);
FORCEPROP 2 LAST SEC 1
J 0
(650 1325);
DISPLAY 0.680851 (650 1325);
PAINT MONO (650 1325);
DISPLAY INVISIBLE (650 1325);
FORCEPROP 2 LAST SEC_TYPE 0402
J 0
(650 1325);
DISPLAY 1.021277 (650 1325);
PAINT ORANGE (650 1325);
DISPLAY INVISIBLE (650 1325);
FORCEADD P3V3_STBY..1
(600 1300);
FORCEPROP 3 LASTPIN (600 1250) SIG_NAME P3V3_STBY\g
J 0
(610 1260);
DISPLAY 0.659574 (610 1260);
PAINT MONO (610 1260);
DISPLAY INVISIBLE (610 1260);
FORCEPROP 1 LAST VOLTAGE +3.3V
J 0
(800 1450);
DISPLAY 1.021277 (800 1450);
PAINT SKYBLUE (800 1450);
DISPLAY INVISIBLE (800 1450);
FORCEPROP 1 LAST SIZE 1B
J 0
(645 1322);
DISPLAY 0.340426 (645 1322);
PAINT GREEN (645 1322);
DISPLAY INVISIBLE (645 1322);
FORCEPROP 2 LAST CDS_LIB mstr_symbols
J 0
(600 1300);
PAINT ORANGE (600 1300);
DISPLAY INVISIBLE (600 1300);
FORCEPROP 1 LAST PATH I150
J 0
(645 1302);
DISPLAY 0.340426 (645 1302);
PAINT GREEN (645 1302);
DISPLAY INVISIBLE (645 1302);
FORCEPROP 1 LAST BODY_TYPE PLUMBING
J 0
(555 1257);
DISPLAY 0.340426 (555 1257);
PAINT GREEN (555 1257);
DISPLAY INVISIBLE (555 1257);
FORCEPROP 1 LAST HDL_POWER P3V3_STBY
J 0
(300 1175);
DISPLAY 0.872340 (300 1175);
PAINT ORANGE (300 1175);
DISPLAY INVISIBLE (300 1175);
FORCEADD OFFPAGE..2
(-975 2600);
FORCEPROP 2 LAST $XR1 145 
J 0
(-666 2600);
DISPLAY 0.638298 (-666 2600);
PAINT MONO (-666 2600);
FORCEPROP 2 LAST $XR0 120 
J 0
(-786 2600);
DISPLAY 0.638298 (-786 2600);
PAINT MONO (-786 2600);
FORCEPROP 2 LAST PATH I153
J 0
(-800 2675);
DISPLAY 1.021277 (-800 2675);
PAINT ORANGE (-800 2675);
DISPLAY INVISIBLE (-800 2675);
FORCEPROP 2 LAST CDS_LIB mstr_standard
J 0
(-975 2600);
PAINT MONO (-975 2600);
DISPLAY INVISIBLE (-975 2600);
FORCEPROP 1 LAST OFFPAGE TRUE
J 0
(-650 2475);
DISPLAY 0.872340 (-650 2475);
PAINT GREEN (-650 2475);
DISPLAY INVISIBLE (-650 2475);
FORCEPROP 1 LAST COMMENT_BODY TRUE
J 0
(-1020 2505);
DISPLAY 0.872340 (-1020 2505);
PAINT GREEN (-1020 2505);
DISPLAY INVISIBLE (-1020 2505);
FORCEADD RES..1
(1350 1875);
FORCEPROP 1 LAST VALUE 10.0
J 2
(1375 1825);
DISPLAY 0.617021 (1375 1825);
PAINT SKYBLUE (1375 1825);
FORCEPROP 1 LASTPIN (1250 1875) $PN 1
J 0
(1262 1887);
DISPLAY 0.617021 (1262 1887);
PAINT ORANGE (1262 1887);
FORCEPROP 1 LAST TOLERANCE 1%
J 0
(1425 1825);
DISPLAY 0.617021 (1425 1825);
PAINT SKYBLUE (1425 1825);
FORCEPROP 1 LASTPIN (1450 1875) $PN 2
J 0
(1412 1887);
DISPLAY 0.617021 (1412 1887);
PAINT ORANGE (1412 1887);
FORCEPROP 1 LAST PART_NUMBER G21796-066
J 0
(1300 1975);
DISPLAY 0.617021 (1300 1975);
PAINT BLUE (1300 1975);
FORCEPROP 1 LAST LOCATION R1D51
J 0
(1300 1925);
DISPLAY 0.617021 (1300 1925);
PAINT AQUA (1300 1925);
FORCEPROP 1 LAST WATTAGE 1/16W
J 2
(1250 1775);
DISPLAY 0.617021 (1250 1775);
PAINT SKYBLUE (1250 1775);
FORCEPROP 1 LAST PACK_TYPE 0402
J 0
(1125 1825);
DISPLAY 0.617021 (1125 1825);
PAINT SKYBLUE (1125 1825);
FORCEPROP 1 LAST MATERIAL CHIP
J 0
(1150 1725);
DISPLAY 0.617021 (1150 1725);
PAINT SKYBLUE (1150 1725);
FORCEPROP 2 LAST CDS_LIB mstr_discrete
J 0
(1350 1875);
PAINT MONO (1350 1875);
DISPLAY INVISIBLE (1350 1875);
FORCEPROP 2 LAST CDS_LOCATION R1D51
J 0
(1300 1925);
DISPLAY 0.617021 (1300 1925);
PAINT AQUA (1300 1925);
DISPLAY INVISIBLE (1300 1925);
FORCEPROP 1 LAST PATH I154
J 0
(1300 2025);
DISPLAY 0.978723 (1300 2025);
PAINT WHITE (1300 2025);
DISPLAY INVISIBLE (1300 2025);
FORCEPROP 0 LAST ROOM HOT_SWAP
J 0
(1300 2075);
DISPLAY 1.021277 (1300 2075);
PAINT ORANGE (1300 2075);
DISPLAY INVISIBLE (1300 2075);
FORCEPROP 2 LAST SEC 1
J 0
(1300 2075);
DISPLAY 0.680851 (1300 2075);
PAINT MONO (1300 2075);
DISPLAY INVISIBLE (1300 2075);
FORCEPROP 2 LAST SEC_TYPE 0402
J 0
(1300 2075);
DISPLAY 1.021277 (1300 2075);
PAINT ORANGE (1300 2075);
DISPLAY INVISIBLE (1300 2075);
FORCEADD CAP..1
(900 1675);
FORCEPROP 1 LAST PART_NUMBER 108427-047
J 0
(950 1525);
DISPLAY 0.617021 (950 1525);
PAINT BLUE (950 1525);
FORCEPROP 1 LAST PACK_TYPE 1206
J 0
(950 1475);
DISPLAY 0.617021 (950 1475);
PAINT SKYBLUE (950 1475);
FORCEPROP 1 LASTPIN (900 1775) $PN 1
J 0
(910 1755);
DISPLAY 0.617021 (910 1755);
PAINT ORANGE (910 1755);
FORCEPROP 1 LASTPIN (900 1575) $PN 2
J 0
(910 1555);
DISPLAY 0.617021 (910 1555);
PAINT ORANGE (910 1555);
FORCEPROP 1 LAST LOCATION C1E2
J 0
(950 1775);
DISPLAY 0.617021 (950 1775);
PAINT AQUA (950 1775);
FORCEPROP 1 LAST MATERIAL X7R
J 0
(950 1575);
DISPLAY 0.617021 (950 1575);
PAINT SKYBLUE (950 1575);
FORCEPROP 1 LAST VOLTAGE 50V
J 0
(950 1675);
DISPLAY 0.617021 (950 1675);
PAINT SKYBLUE (950 1675);
FORCEPROP 1 LAST TOLERANCE 20%
J 0
(950 1625);
DISPLAY 0.617021 (950 1625);
PAINT SKYBLUE (950 1625);
FORCEPROP 1 LAST VALUE 0.068UF
J 0
(950 1725);
DISPLAY 0.617021 (950 1725);
PAINT SKYBLUE (950 1725);
FORCEPROP 2 LAST CDS_LIB mstr_discrete
J 0
(900 1675);
PAINT MONO (900 1675);
DISPLAY INVISIBLE (900 1675);
FORCEPROP 2 LAST CDS_LOCATION C1E2
J 0
(950 1775);
DISPLAY 0.617021 (950 1775);
PAINT AQUA (950 1775);
DISPLAY INVISIBLE (950 1775);
FORCEPROP 1 LAST PATH I155
J 0
(950 1825);
DISPLAY 0.978723 (950 1825);
PAINT WHITE (950 1825);
DISPLAY INVISIBLE (950 1825);
FORCEPROP 2 LAST SEC 1
J 0
(950 1875);
DISPLAY 0.680851 (950 1875);
PAINT MONO (950 1875);
DISPLAY INVISIBLE (950 1875);
FORCEPROP 2 LAST SEC_TYPE 1206
J 0
(950 1875);
DISPLAY 1.021277 (950 1875);
PAINT ORANGE (950 1875);
DISPLAY INVISIBLE (950 1875);
FORCEADD GND..1
(900 1450);
FORCEPROP 3 LASTPIN (900 1500) SIG_NAME GND\g
J 0
(910 1510);
DISPLAY 0.659574 (910 1510);
PAINT MONO (910 1510);
DISPLAY INVISIBLE (910 1510);
FORCEPROP 1 LAST PATH I156
J 0
(975 1450);
DISPLAY 0.872340 (975 1450);
PAINT AQUA (975 1450);
DISPLAY INVISIBLE (975 1450);
FORCEPROP 1 LAST SIZE 1B
J 0
(975 1400);
DISPLAY 0.872340 (975 1400);
PAINT AQUA (975 1400);
DISPLAY INVISIBLE (975 1400);
FORCEPROP 2 LAST CDS_LIB mstr_symbols
J 0
(900 1450);
PAINT MONO (900 1450);
DISPLAY INVISIBLE (900 1450);
FORCEPROP 1 LAST VOLTAGE 0.0V
J 0
(855 1407);
DISPLAY 0.340426 (855 1407);
PAINT SKYBLUE (855 1407);
DISPLAY INVISIBLE (855 1407);
FORCEPROP 1 LAST BODY_TYPE PLUMBING
J 0
(855 1407);
DISPLAY 0.340426 (855 1407);
PAINT GREEN (855 1407);
DISPLAY INVISIBLE (855 1407);
FORCEPROP 1 LAST HDL_POWER GND
J 0
(900 1600);
DISPLAY 0.872340 (900 1600);
PAINT GREEN (900 1600);
DISPLAY INVISIBLE (900 1600);
FORCEADD P3V3_STBY..1
(-1650 2525);
FORCEPROP 3 LASTPIN (-1650 2475) SIG_NAME P3V3_STBY\g
J 0
(-1640 2485);
DISPLAY 0.659574 (-1640 2485);
PAINT MONO (-1640 2485);
DISPLAY INVISIBLE (-1640 2485);
FORCEPROP 1 LAST VOLTAGE +3.3V
J 0
(-1450 2675);
DISPLAY 1.021277 (-1450 2675);
PAINT SKYBLUE (-1450 2675);
DISPLAY INVISIBLE (-1450 2675);
FORCEPROP 1 LAST SIZE 1B
J 0
(-1605 2547);
DISPLAY 0.340426 (-1605 2547);
PAINT GREEN (-1605 2547);
DISPLAY INVISIBLE (-1605 2547);
FORCEPROP 1 LAST PATH I157
J 0
(-1605 2527);
DISPLAY 0.340426 (-1605 2527);
PAINT GREEN (-1605 2527);
DISPLAY INVISIBLE (-1605 2527);
FORCEPROP 2 LAST CDS_LIB mstr_symbols
J 0
(-1650 2525);
PAINT ORANGE (-1650 2525);
DISPLAY INVISIBLE (-1650 2525);
FORCEPROP 1 LAST BODY_TYPE PLUMBING
J 0
(-1695 2482);
DISPLAY 0.340426 (-1695 2482);
PAINT GREEN (-1695 2482);
DISPLAY INVISIBLE (-1695 2482);
FORCEPROP 1 LAST HDL_POWER P3V3_STBY
J 0
(-1950 2400);
DISPLAY 0.872340 (-1950 2400);
PAINT ORANGE (-1950 2400);
DISPLAY INVISIBLE (-1950 2400);
FORCEADD RES..2
(-1650 2350);
FORCEPROP 1 LAST PART_NUMBER G21796-016
J 0
(-1610 2225);
DISPLAY 0.617021 (-1610 2225);
PAINT BLUE (-1610 2225);
FORCEPROP 1 LAST PACK_TYPE 0402
J 0
(-1610 2175);
DISPLAY 0.617021 (-1610 2175);
PAINT SKYBLUE (-1610 2175);
FORCEPROP 1 LAST MATERIAL CHIP
J 0
(-1610 2275);
DISPLAY 0.617021 (-1610 2275);
PAINT SKYBLUE (-1610 2275);
FORCEPROP 1 LASTPIN (-1650 2250) $PN 2
J 0
(-1645 2260);
DISPLAY 0.617021 (-1645 2260);
PAINT ORANGE (-1645 2260);
FORCEPROP 1 LASTPIN (-1650 2450) $PN 1
J 0
(-1645 2412);
DISPLAY 0.617021 (-1645 2412);
PAINT ORANGE (-1645 2412);
FORCEPROP 1 LAST VALUE 10.0K
J 0
(-1605 2425);
DISPLAY 0.617021 (-1605 2425);
PAINT SKYBLUE (-1605 2425);
FORCEPROP 1 LAST LOCATION R1D22
J 0
(-1605 2475);
DISPLAY 0.617021 (-1605 2475);
PAINT AQUA (-1605 2475);
FORCEPROP 1 LAST TOLERANCE 1%
J 0
(-1605 2375);
DISPLAY 0.617021 (-1605 2375);
PAINT SKYBLUE (-1605 2375);
FORCEPROP 1 LAST WATTAGE 1/16W
J 0
(-1610 2325);
DISPLAY 0.617021 (-1610 2325);
PAINT SKYBLUE (-1610 2325);
FORCEPROP 2 LAST SEC_TYPE 0402
J 0
(-1600 2575);
DISPLAY 1.021277 (-1600 2575);
PAINT ORANGE (-1600 2575);
DISPLAY INVISIBLE (-1600 2575);
FORCEPROP 2 LAST SEC 1
J 0
(-1600 2575);
DISPLAY 0.680851 (-1600 2575);
PAINT MONO (-1600 2575);
DISPLAY INVISIBLE (-1600 2575);
FORCEPROP 1 LAST PATH I158
J 0
(-1600 2525);
DISPLAY 0.978723 (-1600 2525);
PAINT WHITE (-1600 2525);
DISPLAY INVISIBLE (-1600 2525);
FORCEPROP 2 LAST ROOM HOT_SWAP
J 0
(-1600 2525);
PAINT MONO (-1600 2525);
DISPLAY INVISIBLE (-1600 2525);
FORCEPROP 2 LAST CDS_LOCATION R1D22
J 0
(-1605 2475);
DISPLAY 0.617021 (-1605 2475);
PAINT AQUA (-1605 2475);
DISPLAY INVISIBLE (-1605 2475);
FORCEPROP 2 LAST CDS_LIB mstr_discrete
J 0
(-1650 2350);
PAINT ORANGE (-1650 2350);
DISPLAY INVISIBLE (-1650 2350);
FORCEADD TPS3700..1
(-350 350);
FORCEPROP 2 LASTPIN (-650 450) $PN 2
J 2
(-660 460);
DISPLAY 0.617021 (-660 460);
PAINT ORANGE (-660 460);
FORCEPROP 1 LAST MATERIAL IC
J 0
(-600 600);
DISPLAY 0.617021 (-600 600);
PAINT SKYBLUE (-600 600);
FORCEPROP 1 LAST LOCATION U9P1
J 0
(-600 650);
DISPLAY 0.617021 (-600 650);
PAINT AQUA (-600 650);
FORCEPROP 2 LASTPIN (-50 450) $PN 6
J 0
(-40 460);
DISPLAY 0.617021 (-40 460);
PAINT ORANGE (-40 460);
FORCEPROP 1 LAST PART_NUMBER H69492-001
J 0
(-600 100);
DISPLAY 0.617021 (-600 100);
PAINT BLUE (-600 100);
FORCEPROP 2 LASTPIN (-650 200) $PN 3
J 2
(-660 160);
DISPLAY 0.617021 (-660 160);
PAINT ORANGE (-660 160);
FORCEPROP 2 LASTPIN (-650 300) $PN 4
J 2
(-660 310);
DISPLAY 0.617021 (-660 310);
PAINT ORANGE (-660 310);
FORCEPROP 2 LASTPIN (-50 350) $PN 1
J 0
(-40 360);
DISPLAY 0.617021 (-40 360);
PAINT ORANGE (-40 360);
FORCEPROP 2 LASTPIN (-50 200) $PN 5
J 0
(-40 210);
DISPLAY 0.617021 (-40 210);
PAINT ORANGE (-40 210);
FORCEPROP 2 LAST CDS_LOCATION U9P1
J 0
(-600 650);
DISPLAY 0.617021 (-600 650);
PAINT AQUA (-600 650);
DISPLAY INVISIBLE (-600 650);
FORCEPROP 2 LAST SEC 1
J 0
(-600 700);
DISPLAY 0.680851 (-600 700);
PAINT MONO (-600 700);
DISPLAY INVISIBLE (-600 700);
FORCEPROP 2 LAST SEC_TYPE SM
J 0
(-600 700);
DISPLAY 1.021277 (-600 700);
PAINT ORANGE (-600 700);
DISPLAY INVISIBLE (-600 700);
FORCEPROP 1 LAST PACK_TYPE SM
J 0
(-600 700);
PAINT SKYBLUE (-600 700);
DISPLAY INVISIBLE (-600 700);
FORCEPROP 2 LAST CDS_LIB mstr_vreg
J 0
(-350 350);
PAINT MONO (-350 350);
DISPLAY INVISIBLE (-350 350);
FORCEPROP 1 LAST CDS_LMAN_SYM_OUTLINE -250,200,250,-200
J 0
(-350 350);
DISPLAY 0.468085 (-350 350);
PAINT GREEN (-350 350);
DISPLAY INVISIBLE (-350 350);
FORCEPROP 1 LAST PATH I163
J 0
(-350 600);
PAINT GREEN (-350 600);
DISPLAY INVISIBLE (-350 600);
FORCEADD TPS3700..1
(-3100 3125);
FORCEPROP 2 LASTPIN (-3400 2975) $PN 3
J 2
(-3410 2985);
DISPLAY 0.617021 (-3410 2985);
PAINT ORANGE (-3410 2985);
FORCEPROP 2 LASTPIN (-2800 3225) $PN 6
J 0
(-2790 3235);
DISPLAY 0.617021 (-2790 3235);
PAINT ORANGE (-2790 3235);
FORCEPROP 2 LASTPIN (-3400 3075) $PN 4
J 2
(-3410 3085);
DISPLAY 0.617021 (-3410 3085);
PAINT ORANGE (-3410 3085);
FORCEPROP 1 LAST MATERIAL IC
J 0
(-3350 3375);
DISPLAY 0.617021 (-3350 3375);
PAINT SKYBLUE (-3350 3375);
FORCEPROP 2 LASTPIN (-3400 3225) $PN 2
J 2
(-3410 3235);
DISPLAY 0.617021 (-3410 3235);
PAINT ORANGE (-3410 3235);
FORCEPROP 2 LASTPIN (-2800 2975) $PN 5
J 0
(-2790 2985);
DISPLAY 0.617021 (-2790 2985);
PAINT ORANGE (-2790 2985);
FORCEPROP 2 LASTPIN (-2800 3125) $PN 1
J 0
(-2790 3135);
DISPLAY 0.617021 (-2790 3135);
PAINT ORANGE (-2790 3135);
FORCEPROP 1 LAST LOCATION U1D2
J 0
(-3350 3425);
DISPLAY 0.617021 (-3350 3425);
PAINT AQUA (-3350 3425);
FORCEPROP 1 LAST PART_NUMBER H69492-001
J 0
(-3350 2875);
DISPLAY 0.617021 (-3350 2875);
PAINT BLUE (-3350 2875);
FORCEPROP 2 LAST CDS_LOCATION U1D2
J 0
(-3350 3425);
DISPLAY 0.617021 (-3350 3425);
PAINT AQUA (-3350 3425);
DISPLAY INVISIBLE (-3350 3425);
FORCEPROP 2 LAST SEC 1
J 0
(-3350 3475);
DISPLAY 0.680851 (-3350 3475);
PAINT MONO (-3350 3475);
DISPLAY INVISIBLE (-3350 3475);
FORCEPROP 2 LAST SEC_TYPE SM
J 0
(-3350 3475);
DISPLAY 1.021277 (-3350 3475);
PAINT ORANGE (-3350 3475);
DISPLAY INVISIBLE (-3350 3475);
FORCEPROP 1 LAST PACK_TYPE SM
J 0
(-3350 3475);
PAINT SKYBLUE (-3350 3475);
DISPLAY INVISIBLE (-3350 3475);
FORCEPROP 1 LAST PATH I170
J 0
(-3100 3375);
PAINT GREEN (-3100 3375);
DISPLAY INVISIBLE (-3100 3375);
FORCEPROP 2 LAST CDS_LIB mstr_vreg
J 0
(-3100 3125);
PAINT MONO (-3100 3125);
DISPLAY INVISIBLE (-3100 3125);
FORCEPROP 1 LAST CDS_LMAN_SYM_OUTLINE -250,200,250,-200
J 0
(-3100 3125);
DISPLAY 0.468085 (-3100 3125);
PAINT GREEN (-3100 3125);
DISPLAY INVISIBLE (-3100 3125);
FORCEADD RES..2
(-4575 2875);
FORCEPROP 1 LASTPIN (-4575 2775) $PN 2
J 0
(-4570 2785);
DISPLAY 0.617021 (-4570 2785);
PAINT ORANGE (-4570 2785);
FORCEPROP 1 LAST WATTAGE 1/16W
J 0
(-4535 2850);
DISPLAY 0.617021 (-4535 2850);
PAINT SKYBLUE (-4535 2850);
FORCEPROP 1 LAST MATERIAL CHIP
J 0
(-4535 2800);
DISPLAY 0.617021 (-4535 2800);
PAINT SKYBLUE (-4535 2800);
FORCEPROP 1 LASTPIN (-4575 2975) $PN 1
J 0
(-4570 2937);
DISPLAY 0.617021 (-4570 2937);
PAINT ORANGE (-4570 2937);
FORCEPROP 1 LAST TOLERANCE 1%
J 0
(-4530 2900);
DISPLAY 0.617021 (-4530 2900);
PAINT SKYBLUE (-4530 2900);
FORCEPROP 1 LAST VALUE 10.0K
J 0
(-4530 2950);
DISPLAY 0.617021 (-4530 2950);
PAINT SKYBLUE (-4530 2950);
FORCEPROP 1 LAST LOCATION R1D12
J 0
(-4530 3000);
DISPLAY 0.617021 (-4530 3000);
PAINT AQUA (-4530 3000);
FORCEPROP 0 LAST CONFIG 64.1002D.6DL
J 0
(-4575 2650);
DISPLAY 0.638298 (-4575 2650);
PAINT BROWN (-4575 2650);
DISPLAY BOTH (-4575 2650);
FORCEPROP 1 LAST PACK_TYPE 0402
J 0
(-4535 2700);
DISPLAY 0.617021 (-4535 2700);
PAINT SKYBLUE (-4535 2700);
FORCEPROP 1 LAST PART_NUMBER G21796-016
J 0
(-4535 2750);
DISPLAY 0.617021 (-4535 2750);
PAINT BLUE (-4535 2750);
FORCEPROP 2 LAST ROOM HOT_SWAP
J 0
(-4525 3050);
PAINT MONO (-4525 3050);
DISPLAY INVISIBLE (-4525 3050);
FORCEPROP 1 LAST PATH I174
J 0
(-4525 3050);
DISPLAY 0.978723 (-4525 3050);
PAINT WHITE (-4525 3050);
DISPLAY INVISIBLE (-4525 3050);
FORCEPROP 2 LAST CDS_LOCATION R1D12
J 0
(-4530 3000);
DISPLAY 0.617021 (-4530 3000);
PAINT AQUA (-4530 3000);
DISPLAY INVISIBLE (-4530 3000);
FORCEPROP 2 LAST SEC 1
J 0
(-4525 3100);
DISPLAY 0.680851 (-4525 3100);
PAINT MONO (-4525 3100);
DISPLAY INVISIBLE (-4525 3100);
FORCEPROP 2 LAST SEC_TYPE 0402
J 0
(-4525 3100);
DISPLAY 1.021277 (-4525 3100);
PAINT ORANGE (-4525 3100);
DISPLAY INVISIBLE (-4525 3100);
FORCEPROP 2 LAST CDS_LIB mstr_discrete
J 0
(-4575 2875);
PAINT MONO (-4575 2875);
DISPLAY INVISIBLE (-4575 2875);
FORCEADD RES..2
(-4150 2450);
FORCEPROP 1 LAST WATTAGE 1/16W
J 0
(-4110 2425);
DISPLAY 0.617021 (-4110 2425);
PAINT SKYBLUE (-4110 2425);
FORCEPROP 0 LAST CONFIG 64.1002D.6DL
J 0
(-4100 2225);
DISPLAY 0.638298 (-4100 2225);
PAINT BROWN (-4100 2225);
DISPLAY BOTH (-4100 2225);
FORCEPROP 1 LAST PACK_TYPE 0402
J 0
(-4110 2275);
DISPLAY 0.617021 (-4110 2275);
PAINT SKYBLUE (-4110 2275);
FORCEPROP 1 LAST PART_NUMBER G21796-016
J 0
(-4110 2325);
DISPLAY 0.617021 (-4110 2325);
PAINT BLUE (-4110 2325);
FORCEPROP 1 LAST MATERIAL CHIP
J 0
(-4110 2375);
DISPLAY 0.617021 (-4110 2375);
PAINT SKYBLUE (-4110 2375);
FORCEPROP 1 LAST TOLERANCE 1%
J 0
(-4105 2475);
DISPLAY 0.617021 (-4105 2475);
PAINT SKYBLUE (-4105 2475);
FORCEPROP 1 LAST VALUE 10.0K
J 0
(-4105 2525);
DISPLAY 0.617021 (-4105 2525);
PAINT SKYBLUE (-4105 2525);
FORCEPROP 1 LAST LOCATION R1D19
J 0
(-4105 2575);
DISPLAY 0.617021 (-4105 2575);
PAINT AQUA (-4105 2575);
FORCEPROP 1 LASTPIN (-4150 2550) $PN 1
J 0
(-4145 2512);
DISPLAY 0.617021 (-4145 2512);
PAINT ORANGE (-4145 2512);
FORCEPROP 1 LASTPIN (-4150 2350) $PN 2
J 0
(-4145 2360);
DISPLAY 0.617021 (-4145 2360);
PAINT ORANGE (-4145 2360);
FORCEPROP 2 LAST CDS_LIB mstr_discrete
J 0
(-4150 2450);
PAINT MONO (-4150 2450);
DISPLAY INVISIBLE (-4150 2450);
FORCEPROP 1 LAST PATH I175
J 0
(-4100 2625);
DISPLAY 0.978723 (-4100 2625);
PAINT WHITE (-4100 2625);
DISPLAY INVISIBLE (-4100 2625);
FORCEPROP 2 LAST ROOM HOT_SWAP
J 0
(-4100 2625);
PAINT MONO (-4100 2625);
DISPLAY INVISIBLE (-4100 2625);
FORCEPROP 2 LAST CDS_LOCATION R1D19
J 0
(-4105 2575);
DISPLAY 0.617021 (-4105 2575);
PAINT AQUA (-4105 2575);
DISPLAY INVISIBLE (-4105 2575);
FORCEPROP 2 LAST SEC 1
J 0
(-4100 2675);
DISPLAY 0.680851 (-4100 2675);
PAINT MONO (-4100 2675);
DISPLAY INVISIBLE (-4100 2675);
FORCEPROP 2 LAST SEC_TYPE 0402
J 0
(-4100 2675);
DISPLAY 1.021277 (-4100 2675);
PAINT ORANGE (-4100 2675);
DISPLAY INVISIBLE (-4100 2675);
FORCEADD GND..1
(-50 50);
FORCEPROP 3 LASTPIN (-50 100) SIG_NAME GND\g
J 0
(-40 110);
DISPLAY 0.659574 (-40 110);
PAINT MONO (-40 110);
DISPLAY INVISIBLE (-40 110);
FORCEPROP 1 LAST VOLTAGE 0.0V
J 0
(-95 7);
DISPLAY 0.340426 (-95 7);
PAINT SKYBLUE (-95 7);
DISPLAY INVISIBLE (-95 7);
FORCEPROP 2 LAST CDS_LIB mstr_symbols
J 0
(-50 50);
PAINT MONO (-50 50);
DISPLAY INVISIBLE (-50 50);
FORCEPROP 1 LAST SIZE 1B
J 0
(25 0);
DISPLAY 0.872340 (25 0);
PAINT AQUA (25 0);
DISPLAY INVISIBLE (25 0);
FORCEPROP 1 LAST PATH I178
J 0
(25 50);
DISPLAY 0.872340 (25 50);
PAINT AQUA (25 50);
DISPLAY INVISIBLE (25 50);
FORCEPROP 1 LAST BODY_TYPE PLUMBING
J 0
(-95 7);
DISPLAY 0.340426 (-95 7);
PAINT GREEN (-95 7);
DISPLAY INVISIBLE (-95 7);
FORCEPROP 1 LAST HDL_POWER GND
J 0
(-50 200);
DISPLAY 0.872340 (-50 200);
PAINT GREEN (-50 200);
DISPLAY INVISIBLE (-50 200);
FORCEADD GND..1
(550 -400);
FORCEPROP 3 LASTPIN (550 -350) SIG_NAME GND\g
J 0
(560 -340);
DISPLAY 0.659574 (560 -340);
PAINT MONO (560 -340);
DISPLAY INVISIBLE (560 -340);
FORCEPROP 1 LAST VOLTAGE 0.0V
J 0
(505 -443);
DISPLAY 0.340426 (505 -443);
PAINT SKYBLUE (505 -443);
DISPLAY INVISIBLE (505 -443);
FORCEPROP 1 LAST PATH I179
J 0
(625 -400);
DISPLAY 0.872340 (625 -400);
PAINT AQUA (625 -400);
DISPLAY INVISIBLE (625 -400);
FORCEPROP 1 LAST SIZE 1B
J 0
(625 -450);
DISPLAY 0.872340 (625 -450);
PAINT AQUA (625 -450);
DISPLAY INVISIBLE (625 -450);
FORCEPROP 2 LAST CDS_LIB mstr_symbols
J 0
(550 -400);
PAINT MONO (550 -400);
DISPLAY INVISIBLE (550 -400);
FORCEPROP 1 LAST BODY_TYPE PLUMBING
J 0
(505 -443);
DISPLAY 0.340426 (505 -443);
PAINT GREEN (505 -443);
DISPLAY INVISIBLE (505 -443);
FORCEPROP 1 LAST HDL_POWER GND
J 0
(550 -250);
DISPLAY 0.872340 (550 -250);
PAINT GREEN (550 -250);
DISPLAY INVISIBLE (550 -250);
FORCEADD AGND0..1
(-4150 2225);
FORCEPROP 3 LASTPIN (-4150 2275) SIG_NAME AGND_HSC\g
J 0
(-4140 2285);
DISPLAY 0.659574 (-4140 2285);
PAINT MONO (-4140 2285);
DISPLAY INVISIBLE (-4140 2285);
FORCEPROP 1 LAST HDL_POWER AGND_HSC
J 1
(-4150 2175);
DISPLAY 0.617021 (-4150 2175);
PAINT GREEN (-4150 2175);
FORCEPROP 1 LAST PATH I180
J 0
(-4075 2225);
DISPLAY 0.872340 (-4075 2225);
PAINT AQUA (-4075 2225);
DISPLAY INVISIBLE (-4075 2225);
FORCEPROP 1 LAST VOLTAGE 0
J 0
(-4150 2225);
PAINT SKYBLUE (-4150 2225);
DISPLAY INVISIBLE (-4150 2225);
FORCEPROP 2 LAST BOM_COST MIO_VRD_MAIN
J 0
(-4125 2200);
PAINT ORANGE (-4125 2200);
DISPLAY INVISIBLE (-4125 2200);
FORCEPROP 2 LAST CDS_LIB mstr_symbols
J 0
(-4150 2225);
PAINT MONO (-4150 2225);
DISPLAY INVISIBLE (-4150 2225);
FORCEPROP 2 LAST ROOM VR_P3V3
J 0
(-4175 2200);
PAINT ORANGE (-4175 2200);
DISPLAY INVISIBLE (-4175 2200);
FORCEPROP 1 LAST BODY_TYPE PLUMBING
J 0
(-4195 2182);
DISPLAY 0.340426 (-4195 2182);
PAINT GREEN (-4195 2182);
DISPLAY INVISIBLE (-4195 2182);
FORCEADD AGND0..1
(-4575 2500);
FORCEPROP 3 LASTPIN (-4575 2550) SIG_NAME AGND_HSC\g
J 0
(-4565 2560);
DISPLAY 0.659574 (-4565 2560);
PAINT MONO (-4565 2560);
DISPLAY INVISIBLE (-4565 2560);
FORCEPROP 1 LAST HDL_POWER AGND_HSC
J 1
(-4550 2425);
DISPLAY 0.617021 (-4550 2425);
PAINT GREEN (-4550 2425);
FORCEPROP 2 LAST ROOM VR_P3V3
J 0
(-4600 2475);
PAINT ORANGE (-4600 2475);
DISPLAY INVISIBLE (-4600 2475);
FORCEPROP 1 LAST PATH I181
J 0
(-4500 2500);
DISPLAY 0.872340 (-4500 2500);
PAINT AQUA (-4500 2500);
DISPLAY INVISIBLE (-4500 2500);
FORCEPROP 2 LAST CDS_LIB mstr_symbols
J 0
(-4575 2500);
PAINT MONO (-4575 2500);
DISPLAY INVISIBLE (-4575 2500);
FORCEPROP 2 LAST BOM_COST MIO_VRD_MAIN
J 0
(-4550 2475);
PAINT ORANGE (-4550 2475);
DISPLAY INVISIBLE (-4550 2475);
FORCEPROP 1 LAST VOLTAGE 0
J 0
(-4575 2500);
PAINT SKYBLUE (-4575 2500);
DISPLAY INVISIBLE (-4575 2500);
FORCEPROP 1 LAST BODY_TYPE PLUMBING
J 0
(-4620 2457);
DISPLAY 0.340426 (-4620 2457);
PAINT GREEN (-4620 2457);
DISPLAY INVISIBLE (-4620 2457);
FORCEADD GND..1
(-2750 2800);
FORCEPROP 3 LASTPIN (-2750 2850) SIG_NAME GND\g
J 0
(-2740 2860);
DISPLAY 0.659574 (-2740 2860);
PAINT MONO (-2740 2860);
DISPLAY INVISIBLE (-2740 2860);
FORCEPROP 1 LAST VOLTAGE 0.0V
J 0
(-2795 2757);
DISPLAY 0.340426 (-2795 2757);
PAINT SKYBLUE (-2795 2757);
DISPLAY INVISIBLE (-2795 2757);
FORCEPROP 1 LAST SIZE 1B
J 0
(-2675 2750);
DISPLAY 0.872340 (-2675 2750);
PAINT AQUA (-2675 2750);
DISPLAY INVISIBLE (-2675 2750);
FORCEPROP 2 LAST CDS_LIB mstr_symbols
J 0
(-2750 2800);
PAINT MONO (-2750 2800);
DISPLAY INVISIBLE (-2750 2800);
FORCEPROP 1 LAST PATH I183
J 0
(-2675 2800);
DISPLAY 0.872340 (-2675 2800);
PAINT AQUA (-2675 2800);
DISPLAY INVISIBLE (-2675 2800);
FORCEPROP 1 LAST BODY_TYPE PLUMBING
J 0
(-2795 2757);
DISPLAY 0.340426 (-2795 2757);
PAINT GREEN (-2795 2757);
DISPLAY INVISIBLE (-2795 2757);
FORCEPROP 1 LAST HDL_POWER GND
J 0
(-2750 2950);
DISPLAY 0.872340 (-2750 2950);
PAINT GREEN (-2750 2950);
DISPLAY INVISIBLE (-2750 2950);
FORCEADD P12V_STBY..1
(-3800 3700);
FORCEPROP 3 LASTPIN (-3800 3650) SIG_NAME P12V_STBY\g
J 0
(-3790 3660);
DISPLAY 0.659574 (-3790 3660);
PAINT MONO (-3790 3660);
DISPLAY INVISIBLE (-3790 3660);
FORCEPROP 1 LAST VOLTAGE 12.0V
J 0
(-3845 3657);
DISPLAY 0.340426 (-3845 3657);
PAINT SKYBLUE (-3845 3657);
DISPLAY INVISIBLE (-3845 3657);
FORCEPROP 1 LAST PATH I184
J 0
(-3755 3702);
DISPLAY 0.340426 (-3755 3702);
PAINT GREEN (-3755 3702);
DISPLAY INVISIBLE (-3755 3702);
FORCEPROP 2 LAST CDS_LIB mstr_symbols
J 0
(-3800 3700);
PAINT MONO (-3800 3700);
DISPLAY INVISIBLE (-3800 3700);
FORCEPROP 1 LAST SIZE 1B
J 0
(-3755 3722);
DISPLAY 0.340426 (-3755 3722);
PAINT GREEN (-3755 3722);
DISPLAY INVISIBLE (-3755 3722);
FORCEPROP 1 LAST BODY_TYPE PLUMBING
J 0
(-3845 3657);
DISPLAY 0.340426 (-3845 3657);
PAINT GREEN (-3845 3657);
DISPLAY INVISIBLE (-3845 3657);
FORCEPROP 1 LAST HDL_POWER P12V_STBY
J 0
(-4100 3575);
DISPLAY 0.872340 (-4100 3575);
PAINT ORANGE (-4100 3575);
DISPLAY INVISIBLE (-4100 3575);
FORCEADD CAP_A..1
R 2
(-825 775);
FORCEPROP 1 LASTPIN (-825 675) $PN 2
J 2
(-835 655);
DISPLAY 0.617021 (-835 655);
PAINT ORANGE (-835 655);
FORCEPROP 1 LAST MATERIAL X7R
J 2
(-875 675);
DISPLAY 0.617021 (-875 675);
PAINT SKYBLUE (-875 675);
FORCEPROP 1 LASTPIN (-825 875) $PN 1
J 2
(-835 855);
DISPLAY 0.617021 (-835 855);
PAINT ORANGE (-835 855);
FORCEPROP 1 LAST LOCATION C9P6
J 2
(-875 875);
DISPLAY 0.617021 (-875 875);
PAINT AQUA (-875 875);
FORCEPROP 1 LAST VALUE 0.1UF
J 2
(-875 825);
DISPLAY 0.617021 (-875 825);
PAINT SKYBLUE (-875 825);
FORCEPROP 1 LAST TOLERANCE 10%
J 2
(-875 725);
DISPLAY 0.617021 (-875 725);
PAINT SKYBLUE (-875 725);
FORCEPROP 1 LAST PACK_TYPE 0402V
J 2
(-950 575);
DISPLAY 0.617021 (-950 575);
PAINT SKYBLUE (-950 575);
FORCEPROP 1 LAST PART_NUMBER A36096-030
J 2
(-875 625);
DISPLAY 0.617021 (-875 625);
PAINT BLUE (-875 625);
FORCEPROP 1 LAST VOLTAGE 16V
J 2
(-875 775);
DISPLAY 0.617021 (-875 775);
PAINT SKYBLUE (-875 775);
FORCEPROP 2 LAST SEC_TYPE 0402V
J 0
(-875 975);
DISPLAY 1.021277 (-875 975);
PAINT ORANGE (-875 975);
DISPLAY INVISIBLE (-875 975);
FORCEPROP 2 LAST SEC 1
J 0
(-875 975);
DISPLAY 0.680851 (-875 975);
PAINT MONO (-875 975);
DISPLAY INVISIBLE (-875 975);
FORCEPROP 2 LAST CDS_SEC 1
J 0
(-875 925);
PAINT ORANGE (-875 925);
DISPLAY INVISIBLE (-875 925);
FORCEPROP 2 LAST CDS_LIB dev_discrete
J 0
(-825 775);
PAINT ORANGE (-825 775);
DISPLAY INVISIBLE (-825 775);
FORCEPROP 2 LAST CDS_LOCATION C9P6
J 2
(-875 875);
DISPLAY 0.617021 (-875 875);
PAINT AQUA (-875 875);
DISPLAY INVISIBLE (-875 875);
FORCEPROP 0 LAST ROOM HOT_SWAP
J 0
(-875 925);
DISPLAY 1.021277 (-875 925);
PAINT ORANGE (-875 925);
DISPLAY INVISIBLE (-875 925);
FORCEPROP 1 LAST PATH I185
J 2
(-875 925);
DISPLAY 0.978723 (-875 925);
PAINT WHITE (-875 925);
DISPLAY INVISIBLE (-875 925);
FORCEADD AGND0..1
(-825 625);
FORCEPROP 3 LASTPIN (-825 675) SIG_NAME AGND_HSC\g
J 0
(-815 685);
DISPLAY 0.659574 (-815 685);
PAINT MONO (-815 685);
DISPLAY INVISIBLE (-815 685);
FORCEPROP 1 LAST HDL_POWER AGND_HSC
J 1
(-825 575);
DISPLAY 0.617021 (-825 575);
PAINT GREEN (-825 575);
FORCEPROP 2 LAST ROOM VR_P3V3
J 0
(-850 600);
PAINT ORANGE (-850 600);
DISPLAY INVISIBLE (-850 600);
FORCEPROP 2 LAST BOM_COST MIO_VRD_MAIN
J 0
(-800 600);
PAINT ORANGE (-800 600);
DISPLAY INVISIBLE (-800 600);
FORCEPROP 2 LAST CDS_LIB mstr_symbols
J 0
(-825 625);
PAINT MONO (-825 625);
DISPLAY INVISIBLE (-825 625);
FORCEPROP 1 LAST VOLTAGE 0
J 0
(-825 625);
PAINT SKYBLUE (-825 625);
DISPLAY INVISIBLE (-825 625);
FORCEPROP 1 LAST PATH I186
J 0
(-750 625);
DISPLAY 0.872340 (-750 625);
PAINT AQUA (-750 625);
DISPLAY INVISIBLE (-750 625);
FORCEPROP 1 LAST BODY_TYPE PLUMBING
J 0
(-870 582);
DISPLAY 0.340426 (-870 582);
PAINT GREEN (-870 582);
DISPLAY INVISIBLE (-870 582);
FORCEADD CAP_A..1
R 2
(-3800 3425);
FORCEPROP 1 LASTPIN (-3800 3325) $PN 2
J 2
(-3810 3305);
DISPLAY 0.617021 (-3810 3305);
PAINT ORANGE (-3810 3305);
FORCEPROP 1 LASTPIN (-3800 3525) $PN 1
J 2
(-3810 3505);
DISPLAY 0.617021 (-3810 3505);
PAINT ORANGE (-3810 3505);
FORCEPROP 1 LAST VOLTAGE 16V
J 2
(-3850 3425);
DISPLAY 0.617021 (-3850 3425);
PAINT SKYBLUE (-3850 3425);
FORCEPROP 1 LAST MATERIAL X7R
J 2
(-3850 3325);
DISPLAY 0.617021 (-3850 3325);
PAINT SKYBLUE (-3850 3325);
FORCEPROP 1 LAST TOLERANCE 10%
J 2
(-3850 3375);
DISPLAY 0.617021 (-3850 3375);
PAINT SKYBLUE (-3850 3375);
FORCEPROP 1 LAST VALUE 0.1UF
J 2
(-3850 3475);
DISPLAY 0.617021 (-3850 3475);
PAINT SKYBLUE (-3850 3475);
FORCEPROP 1 LAST LOCATION C1D9
J 2
(-3850 3525);
DISPLAY 0.617021 (-3850 3525);
PAINT AQUA (-3850 3525);
FORCEPROP 1 LAST PACK_TYPE 0402V
J 2
(-3850 3225);
DISPLAY 0.617021 (-3850 3225);
PAINT SKYBLUE (-3850 3225);
FORCEPROP 1 LAST PART_NUMBER A36096-030
J 2
(-3850 3275);
DISPLAY 0.617021 (-3850 3275);
PAINT BLUE (-3850 3275);
FORCEPROP 2 LAST CDS_LOCATION C1D9
J 2
(-3850 3525);
DISPLAY 0.617021 (-3850 3525);
PAINT AQUA (-3850 3525);
DISPLAY INVISIBLE (-3850 3525);
FORCEPROP 2 LAST CDS_LIB dev_discrete
J 0
(-3800 3425);
PAINT ORANGE (-3800 3425);
DISPLAY INVISIBLE (-3800 3425);
FORCEPROP 2 LAST CDS_SEC 1
J 0
(-3850 3575);
PAINT ORANGE (-3850 3575);
DISPLAY INVISIBLE (-3850 3575);
FORCEPROP 0 LAST ROOM HOT_SWAP
J 0
(-3850 3575);
DISPLAY 1.021277 (-3850 3575);
PAINT ORANGE (-3850 3575);
DISPLAY INVISIBLE (-3850 3575);
FORCEPROP 1 LAST PATH I187
J 2
(-3850 3575);
DISPLAY 0.978723 (-3850 3575);
PAINT WHITE (-3850 3575);
DISPLAY INVISIBLE (-3850 3575);
FORCEPROP 2 LAST SEC_TYPE 0402V
J 0
(-3850 3625);
DISPLAY 1.021277 (-3850 3625);
PAINT ORANGE (-3850 3625);
DISPLAY INVISIBLE (-3850 3625);
FORCEPROP 2 LAST SEC 1
J 0
(-3850 3625);
DISPLAY 0.680851 (-3850 3625);
PAINT MONO (-3850 3625);
DISPLAY INVISIBLE (-3850 3625);
FORCEADD AGND0..1
(-3800 3175);
FORCEPROP 3 LASTPIN (-3800 3225) SIG_NAME AGND_HSC\g
J 0
(-3790 3235);
DISPLAY 0.659574 (-3790 3235);
PAINT MONO (-3790 3235);
DISPLAY INVISIBLE (-3790 3235);
FORCEPROP 1 LAST HDL_POWER AGND_HSC
J 1
(-3800 3125);
DISPLAY 0.617021 (-3800 3125);
PAINT GREEN (-3800 3125);
FORCEPROP 2 LAST BOM_COST MIO_VRD_MAIN
J 0
(-3775 3150);
PAINT ORANGE (-3775 3150);
DISPLAY INVISIBLE (-3775 3150);
FORCEPROP 2 LAST ROOM VR_P3V3
J 0
(-3825 3150);
PAINT ORANGE (-3825 3150);
DISPLAY INVISIBLE (-3825 3150);
FORCEPROP 1 LAST PATH I188
J 0
(-3725 3175);
DISPLAY 0.872340 (-3725 3175);
PAINT AQUA (-3725 3175);
DISPLAY INVISIBLE (-3725 3175);
FORCEPROP 1 LAST VOLTAGE 0
J 0
(-3800 3175);
PAINT SKYBLUE (-3800 3175);
DISPLAY INVISIBLE (-3800 3175);
FORCEPROP 2 LAST CDS_LIB mstr_symbols
J 0
(-3800 3175);
PAINT MONO (-3800 3175);
DISPLAY INVISIBLE (-3800 3175);
FORCEPROP 1 LAST BODY_TYPE PLUMBING
J 0
(-3845 3132);
DISPLAY 0.340426 (-3845 3132);
PAINT GREEN (-3845 3132);
DISPLAY INVISIBLE (-3845 3132);
FORCEADD P3V3_STBY..1
(-2600 3850);
FORCEPROP 3 LASTPIN (-2600 3800) SIG_NAME P3V3_STBY\g
J 0
(-2590 3810);
DISPLAY 0.659574 (-2590 3810);
PAINT MONO (-2590 3810);
DISPLAY INVISIBLE (-2590 3810);
FORCEPROP 1 LAST VOLTAGE +3.3V
J 0
(-2400 4000);
DISPLAY 1.021277 (-2400 4000);
PAINT SKYBLUE (-2400 4000);
DISPLAY INVISIBLE (-2400 4000);
FORCEPROP 1 LAST SIZE 1B
J 0
(-2555 3872);
DISPLAY 0.340426 (-2555 3872);
PAINT GREEN (-2555 3872);
DISPLAY INVISIBLE (-2555 3872);
FORCEPROP 1 LAST PATH I190
J 0
(-2555 3852);
DISPLAY 0.340426 (-2555 3852);
PAINT GREEN (-2555 3852);
DISPLAY INVISIBLE (-2555 3852);
FORCEPROP 2 LAST CDS_LIB mstr_symbols
J 0
(-2600 3850);
PAINT MONO (-2600 3850);
DISPLAY INVISIBLE (-2600 3850);
FORCEPROP 1 LAST BODY_TYPE PLUMBING
J 0
(-2645 3807);
DISPLAY 0.340426 (-2645 3807);
PAINT GREEN (-2645 3807);
DISPLAY INVISIBLE (-2645 3807);
FORCEPROP 1 LAST HDL_POWER P3V3_STBY
J 0
(-2900 3725);
DISPLAY 0.872340 (-2900 3725);
PAINT ORANGE (-2900 3725);
DISPLAY INVISIBLE (-2900 3725);
FORCEADD RES..2
(-2950 3550);
FORCEPROP 1 LASTPIN (-2950 3650) $PN 1
J 0
(-2945 3612);
DISPLAY 0.617021 (-2945 3612);
PAINT ORANGE (-2945 3612);
FORCEPROP 1 LASTPIN (-2950 3450) $PN 2
J 0
(-2945 3460);
DISPLAY 0.617021 (-2945 3460);
PAINT ORANGE (-2945 3460);
FORCEPROP 1 LAST TOLERANCE 1%
J 0
(-2905 3575);
DISPLAY 0.617021 (-2905 3575);
PAINT SKYBLUE (-2905 3575);
FORCEPROP 1 LAST MATERIAL CHIP
J 0
(-2910 3475);
DISPLAY 0.617021 (-2910 3475);
PAINT SKYBLUE (-2910 3475);
FORCEPROP 1 LAST PACK_TYPE 0402
J 0
(-2910 3375);
DISPLAY 0.617021 (-2910 3375);
PAINT SKYBLUE (-2910 3375);
FORCEPROP 1 LAST PART_NUMBER G21796-016
J 0
(-2910 3425);
DISPLAY 0.617021 (-2910 3425);
PAINT BLUE (-2910 3425);
FORCEPROP 1 LAST WATTAGE 1/16W
J 0
(-2910 3525);
DISPLAY 0.617021 (-2910 3525);
PAINT SKYBLUE (-2910 3525);
FORCEPROP 1 LAST VALUE 10.0K
J 0
(-2905 3625);
DISPLAY 0.617021 (-2905 3625);
PAINT SKYBLUE (-2905 3625);
FORCEPROP 1 LAST LOCATION R1D23
J 0
(-2905 3675);
DISPLAY 0.617021 (-2905 3675);
PAINT AQUA (-2905 3675);
FORCEPROP 1 LAST PATH I191
J 0
(-2900 3725);
DISPLAY 0.978723 (-2900 3725);
PAINT WHITE (-2900 3725);
DISPLAY INVISIBLE (-2900 3725);
FORCEPROP 2 LAST ROOM HOT_SWAP
J 0
(-2900 3725);
PAINT MONO (-2900 3725);
DISPLAY INVISIBLE (-2900 3725);
FORCEPROP 2 LAST CDS_LOCATION R1D23
J 0
(-2905 3675);
DISPLAY 0.617021 (-2905 3675);
PAINT AQUA (-2905 3675);
DISPLAY INVISIBLE (-2905 3675);
FORCEPROP 2 LAST SEC 1
J 0
(-2900 3775);
DISPLAY 0.680851 (-2900 3775);
PAINT MONO (-2900 3775);
DISPLAY INVISIBLE (-2900 3775);
FORCEPROP 2 LAST SEC_TYPE 0402
J 0
(-2900 3775);
DISPLAY 1.021277 (-2900 3775);
PAINT ORANGE (-2900 3775);
DISPLAY INVISIBLE (-2900 3775);
FORCEPROP 2 LAST CDS_LIB mstr_discrete
J 0
(-2950 3550);
PAINT MONO (-2950 3550);
DISPLAY INVISIBLE (-2950 3550);
FORCEADD RES..2
(275 1075);
FORCEPROP 1 LAST LOCATION R9P10
J 0
(320 1200);
DISPLAY 0.617021 (320 1200);
PAINT AQUA (320 1200);
FORCEPROP 1 LAST PACK_TYPE 0402
J 0
(315 900);
DISPLAY 0.617021 (315 900);
PAINT SKYBLUE (315 900);
FORCEPROP 1 LASTPIN (275 1175) $PN 1
J 0
(280 1137);
DISPLAY 0.617021 (280 1137);
PAINT ORANGE (280 1137);
FORCEPROP 1 LAST WATTAGE 1/16W
J 0
(315 1050);
DISPLAY 0.617021 (315 1050);
PAINT SKYBLUE (315 1050);
FORCEPROP 1 LASTPIN (275 975) $PN 2
J 0
(280 985);
DISPLAY 0.617021 (280 985);
PAINT ORANGE (280 985);
FORCEPROP 1 LAST MATERIAL CHIP
J 0
(315 1000);
DISPLAY 0.617021 (315 1000);
PAINT SKYBLUE (315 1000);
FORCEPROP 1 LAST VALUE 10.0K
J 0
(320 1150);
DISPLAY 0.617021 (320 1150);
PAINT SKYBLUE (320 1150);
FORCEPROP 1 LAST TOLERANCE 1%
J 0
(320 1100);
DISPLAY 0.617021 (320 1100);
PAINT SKYBLUE (320 1100);
FORCEPROP 1 LAST PART_NUMBER G21796-016
J 0
(315 950);
DISPLAY 0.617021 (315 950);
PAINT BLUE (315 950);
FORCEPROP 2 LAST CDS_LIB mstr_discrete
J 0
(275 1075);
PAINT MONO (275 1075);
DISPLAY INVISIBLE (275 1075);
FORCEPROP 2 LAST ROOM HOT_SWAP
J 0
(325 1250);
PAINT MONO (325 1250);
DISPLAY INVISIBLE (325 1250);
FORCEPROP 1 LAST PATH I192
J 0
(325 1250);
DISPLAY 0.978723 (325 1250);
PAINT WHITE (325 1250);
DISPLAY INVISIBLE (325 1250);
FORCEPROP 2 LAST CDS_LOCATION R9P10
J 0
(320 1200);
DISPLAY 0.617021 (320 1200);
PAINT AQUA (320 1200);
DISPLAY INVISIBLE (320 1200);
FORCEPROP 2 LAST SEC 1
J 0
(325 1300);
DISPLAY 0.680851 (325 1300);
PAINT MONO (325 1300);
DISPLAY INVISIBLE (325 1300);
FORCEPROP 2 LAST SEC_TYPE 0402
J 0
(325 1300);
DISPLAY 1.021277 (325 1300);
PAINT ORANGE (325 1300);
DISPLAY INVISIBLE (325 1300);
FORCEADD P3V3_STBY..1
(275 1300);
FORCEPROP 3 LASTPIN (275 1250) SIG_NAME P3V3_STBY\g
J 0
(285 1260);
DISPLAY 0.659574 (285 1260);
PAINT MONO (285 1260);
DISPLAY INVISIBLE (285 1260);
FORCEPROP 1 LAST VOLTAGE +3.3V
J 0
(475 1450);
DISPLAY 1.021277 (475 1450);
PAINT SKYBLUE (475 1450);
DISPLAY INVISIBLE (475 1450);
FORCEPROP 1 LAST SIZE 1B
J 0
(320 1322);
DISPLAY 0.340426 (320 1322);
PAINT GREEN (320 1322);
DISPLAY INVISIBLE (320 1322);
FORCEPROP 1 LAST PATH I194
J 0
(320 1302);
DISPLAY 0.340426 (320 1302);
PAINT GREEN (320 1302);
DISPLAY INVISIBLE (320 1302);
FORCEPROP 2 LAST CDS_LIB mstr_symbols
J 0
(275 1300);
PAINT MONO (275 1300);
DISPLAY INVISIBLE (275 1300);
FORCEPROP 1 LAST BODY_TYPE PLUMBING
J 0
(230 1257);
DISPLAY 0.340426 (230 1257);
PAINT GREEN (230 1257);
DISPLAY INVISIBLE (230 1257);
FORCEPROP 1 LAST HDL_POWER P3V3_STBY
J 0
(-25 1175);
DISPLAY 0.872340 (-25 1175);
PAINT ORANGE (-25 1175);
DISPLAY INVISIBLE (-25 1175);
FORCEADD FET_N_DUAL..5
(-2000 3325);
FORCEPROP 1 LASTPIN (-2000 3125) $PN 1
J 2
(-1942 3125);
DISPLAY 0.617021 (-1942 3125);
PAINT WHITE (-1942 3125);
FORCEPROP 1 LAST MATERIAL FET
J 0
(-1800 3225);
DISPLAY 0.617021 (-1800 3225);
PAINT SKYBLUE (-1800 3225);
FORCEPROP 1 LASTPIN (-2000 3525) $PN 6
J 2
(-1947 3490);
DISPLAY 0.617021 (-1947 3490);
PAINT WHITE (-1947 3490);
FORCEPROP 1 LASTPIN (-2200 3225) $PN 2
J 2
(-2197 3240);
DISPLAY 0.617021 (-2197 3240);
PAINT WHITE (-2197 3240);
FORCEPROP 1 LAST PART_NUMBER D24280-001
J 0
(-1800 3125);
DISPLAY 0.617021 (-1800 3125);
PAINT BLUE (-1800 3125);
FORCEPROP 1 LAST LOCATION Q9P1
J 0
(-1800 3325);
DISPLAY 0.617021 (-1800 3325);
PAINT AQUA (-1800 3325);
FORCEPROP 1 LAST VALUE 2N7002DW
J 0
(-1800 3275);
DISPLAY 0.617021 (-1800 3275);
PAINT SKYBLUE (-1800 3275);
FORCEPROP 1 LAST PACK_TYPE SMLF
J 0
(-1800 3175);
DISPLAY 0.978723 (-1800 3175);
PAINT SKYBLUE (-1800 3175);
DISPLAY INVISIBLE (-1800 3175);
FORCEPROP 2 LAST SEC_TYPE SMLF
J 0
(-1800 3425);
DISPLAY 1.021277 (-1800 3425);
PAINT ORANGE (-1800 3425);
DISPLAY INVISIBLE (-1800 3425);
FORCEPROP 2 LAST SEC 1
J 0
(-1800 3425);
DISPLAY 0.680851 (-1800 3425);
PAINT MONO (-1800 3425);
DISPLAY INVISIBLE (-1800 3425);
FORCEPROP 2 LAST CDS_LOCATION Q9P1
J 0
(-1800 3325);
DISPLAY 0.617021 (-1800 3325);
PAINT AQUA (-1800 3325);
DISPLAY INVISIBLE (-1800 3325);
FORCEPROP 1 LAST PATH I196
J 0
(-1800 3375);
DISPLAY 0.978723 (-1800 3375);
PAINT BLUE (-1800 3375);
DISPLAY INVISIBLE (-1800 3375);
FORCEPROP 2 LAST ROOM HOT_SWAP
J 0
(-1800 3425);
PAINT MONO (-1800 3425);
DISPLAY INVISIBLE (-1800 3425);
FORCEPROP 2 LAST CDS_LIB mstr_discrete
J 0
(-2000 3325);
PAINT MONO (-2000 3325);
DISPLAY INVISIBLE (-2000 3325);
FORCEADD GND..1
(-2000 3025);
FORCEPROP 3 LASTPIN (-2000 3075) SIG_NAME GND\g
J 0
(-1990 3085);
DISPLAY 0.659574 (-1990 3085);
PAINT MONO (-1990 3085);
DISPLAY INVISIBLE (-1990 3085);
FORCEPROP 1 LAST VOLTAGE 0.0V
J 0
(-2045 2982);
DISPLAY 0.340426 (-2045 2982);
PAINT SKYBLUE (-2045 2982);
DISPLAY INVISIBLE (-2045 2982);
FORCEPROP 1 LAST SIZE 1B
J 0
(-1925 2975);
DISPLAY 0.872340 (-1925 2975);
PAINT AQUA (-1925 2975);
DISPLAY INVISIBLE (-1925 2975);
FORCEPROP 2 LAST CDS_LIB mstr_symbols
J 0
(-2000 3025);
PAINT MONO (-2000 3025);
DISPLAY INVISIBLE (-2000 3025);
FORCEPROP 1 LAST PATH I197
J 0
(-1925 3025);
DISPLAY 0.872340 (-1925 3025);
PAINT AQUA (-1925 3025);
DISPLAY INVISIBLE (-1925 3025);
FORCEPROP 1 LAST BODY_TYPE PLUMBING
J 0
(-2045 2982);
DISPLAY 0.340426 (-2045 2982);
PAINT GREEN (-2045 2982);
DISPLAY INVISIBLE (-2045 2982);
FORCEPROP 1 LAST HDL_POWER GND
J 0
(-2000 3175);
DISPLAY 0.872340 (-2000 3175);
PAINT GREEN (-2000 3175);
DISPLAY INVISIBLE (-2000 3175);
FORCEADD FET_N_DUAL..5
(550 -100);
FORCEPROP 1 LASTPIN (550 -300) $PN 4
J 2
(608 -300);
DISPLAY 0.617021 (608 -300);
PAINT WHITE (608 -300);
FORCEPROP 1 LASTPIN (550 100) $PN 3
J 2
(603 65);
DISPLAY 0.617021 (603 65);
PAINT WHITE (603 65);
FORCEPROP 1 LASTPIN (350 -200) $PN 5
J 2
(353 -185);
DISPLAY 0.617021 (353 -185);
PAINT WHITE (353 -185);
FORCEPROP 1 LAST PART_NUMBER D24280-001
J 0
(750 -300);
DISPLAY 0.617021 (750 -300);
PAINT BLUE (750 -300);
FORCEPROP 1 LAST LOCATION Q9P1
J 0
(750 -100);
DISPLAY 0.617021 (750 -100);
PAINT AQUA (750 -100);
FORCEPROP 1 LAST MATERIAL FET
J 0
(750 -200);
DISPLAY 0.617021 (750 -200);
PAINT SKYBLUE (750 -200);
FORCEPROP 1 LAST VALUE 2N7002DW
J 0
(750 -150);
DISPLAY 0.617021 (750 -150);
PAINT SKYBLUE (750 -150);
FORCEPROP 2 LAST CDS_LIB mstr_discrete
J 0
(550 -100);
PAINT MONO (550 -100);
DISPLAY INVISIBLE (550 -100);
FORCEPROP 1 LAST PATH I199
J 0
(750 -50);
DISPLAY 0.978723 (750 -50);
PAINT BLUE (750 -50);
DISPLAY INVISIBLE (750 -50);
FORCEPROP 2 LAST CDS_LOCATION Q9P1
J 0
(750 -100);
DISPLAY 0.617021 (750 -100);
PAINT AQUA (750 -100);
DISPLAY INVISIBLE (750 -100);
FORCEPROP 1 LAST PACK_TYPE SMLF
J 0
(750 -250);
DISPLAY 0.978723 (750 -250);
PAINT SKYBLUE (750 -250);
DISPLAY INVISIBLE (750 -250);
FORCEPROP 2 LAST ROOM HOT_SWAP
J 0
(750 0);
PAINT MONO (750 0);
DISPLAY INVISIBLE (750 0);
FORCEPROP 2 LAST SEC 2
J 0
(750 0);
DISPLAY 0.680851 (750 0);
PAINT MONO (750 0);
DISPLAY INVISIBLE (750 0);
FORCEPROP 2 LAST SEC_TYPE SMLF
J 0
(750 0);
DISPLAY 1.021277 (750 0);
PAINT ORANGE (750 0);
DISPLAY INVISIBLE (750 0);
FORCEADD TPS3700..1
(-3425 -150);
FORCEPROP 1 LAST LOCATION U9P2
J 0
(-3675 150);
DISPLAY 0.617021 (-3675 150);
PAINT AQUA (-3675 150);
FORCEPROP 2 LASTPIN (-3725 -200) $PN 4
J 2
(-3735 -190);
DISPLAY 0.617021 (-3735 -190);
PAINT MONO (-3735 -190);
FORCEPROP 2 LASTPIN (-3725 -300) $PN 3
J 2
(-3735 -290);
DISPLAY 0.617021 (-3735 -290);
PAINT MONO (-3735 -290);
FORCEPROP 2 LASTPIN (-3725 -50) $PN 2
J 2
(-3735 -40);
DISPLAY 0.617021 (-3735 -40);
PAINT MONO (-3735 -40);
FORCEPROP 1 LAST PART_NUMBER H69492-001
J 0
(-3675 -400);
DISPLAY 0.617021 (-3675 -400);
PAINT BLUE (-3675 -400);
FORCEPROP 2 LASTPIN (-3125 -300) $PN 5
J 0
(-3115 -290);
DISPLAY 0.617021 (-3115 -290);
PAINT MONO (-3115 -290);
FORCEPROP 1 LAST MATERIAL IC
J 0
(-3675 100);
DISPLAY 0.617021 (-3675 100);
PAINT SKYBLUE (-3675 100);
FORCEPROP 2 LASTPIN (-3125 -150) $PN 1
J 0
(-3115 -140);
DISPLAY 0.617021 (-3115 -140);
PAINT MONO (-3115 -140);
FORCEPROP 2 LASTPIN (-3125 -50) $PN 6
J 0
(-3115 -40);
DISPLAY 0.617021 (-3115 -40);
PAINT MONO (-3115 -40);
FORCEPROP 1 LAST CDS_LMAN_SYM_OUTLINE -250,200,250,-200
J 0
(-3425 -150);
DISPLAY 0.468085 (-3425 -150);
PAINT GREEN (-3425 -150);
DISPLAY INVISIBLE (-3425 -150);
FORCEPROP 2 LAST CDS_LIB mstr_vreg
J 0
(-3425 -150);
PAINT MONO (-3425 -150);
DISPLAY INVISIBLE (-3425 -150);
FORCEPROP 2 LAST CDS_LOCATION U9P2
J 0
(-3675 150);
DISPLAY 0.617021 (-3675 150);
PAINT AQUA (-3675 150);
DISPLAY INVISIBLE (-3675 150);
FORCEPROP 2 LAST $SEC 1
J 0
(-3675 200);
PAINT MONO (-3675 200);
DISPLAY INVISIBLE (-3675 200);
FORCEPROP 2 LAST CDS_SEC 1
J 0
(-3675 200);
PAINT MONO (-3675 200);
DISPLAY INVISIBLE (-3675 200);
FORCEPROP 1 LAST PACK_TYPE SM
J 0
(-3675 200);
PAINT SKYBLUE (-3675 200);
DISPLAY INVISIBLE (-3675 200);
FORCEPROP 1 LAST PATH I200
J 0
(-3425 100);
PAINT GREEN (-3425 100);
DISPLAY INVISIBLE (-3425 100);
FORCEADD CAP_A..1
R 2
(-3450 500);
FORCEPROP 1 LAST LOCATION C9P11
J 2
(-3500 600);
DISPLAY 0.617021 (-3500 600);
PAINT AQUA (-3500 600);
FORCEPROP 1 LASTPIN (-3450 600) $PN 1
J 2
(-3460 580);
DISPLAY 0.617021 (-3460 580);
PAINT ORANGE (-3460 580);
FORCEPROP 1 LASTPIN (-3450 400) $PN 2
J 2
(-3460 380);
DISPLAY 0.617021 (-3460 380);
PAINT ORANGE (-3460 380);
FORCEPROP 1 LAST VOLTAGE 16V
J 2
(-3500 500);
DISPLAY 0.617021 (-3500 500);
PAINT SKYBLUE (-3500 500);
FORCEPROP 1 LAST PART_NUMBER A36096-030
J 2
(-3500 350);
DISPLAY 0.617021 (-3500 350);
PAINT BLUE (-3500 350);
FORCEPROP 1 LAST PACK_TYPE 0402V
J 2
(-3500 300);
DISPLAY 0.617021 (-3500 300);
PAINT SKYBLUE (-3500 300);
FORCEPROP 1 LAST TOLERANCE 10%
J 2
(-3500 450);
DISPLAY 0.617021 (-3500 450);
PAINT SKYBLUE (-3500 450);
FORCEPROP 1 LAST MATERIAL X7R
J 2
(-3500 400);
DISPLAY 0.617021 (-3500 400);
PAINT SKYBLUE (-3500 400);
FORCEPROP 1 LAST VALUE 0.1UF
J 2
(-3500 550);
DISPLAY 0.617021 (-3500 550);
PAINT SKYBLUE (-3500 550);
FORCEPROP 2 LAST CDS_LIB dev_discrete
J 0
(-3450 500);
PAINT ORANGE (-3450 500);
DISPLAY INVISIBLE (-3450 500);
FORCEPROP 1 LAST PATH I201
J 2
(-3500 650);
DISPLAY 0.978723 (-3500 650);
PAINT WHITE (-3500 650);
DISPLAY INVISIBLE (-3500 650);
FORCEPROP 0 LAST ROOM HOT_SWAP
J 0
(-3500 650);
DISPLAY 1.021277 (-3500 650);
PAINT ORANGE (-3500 650);
DISPLAY INVISIBLE (-3500 650);
FORCEPROP 2 LAST CDS_LOCATION C9P11
J 2
(-3500 600);
DISPLAY 0.617021 (-3500 600);
PAINT AQUA (-3500 600);
DISPLAY INVISIBLE (-3500 600);
FORCEPROP 2 LAST CDS_SEC 1
J 0
(-3500 650);
PAINT ORANGE (-3500 650);
DISPLAY INVISIBLE (-3500 650);
FORCEPROP 2 LAST SEC_TYPE 0402V
J 0
(-3500 700);
DISPLAY 1.021277 (-3500 700);
PAINT ORANGE (-3500 700);
DISPLAY INVISIBLE (-3500 700);
FORCEPROP 2 LAST SEC 1
J 0
(-3500 700);
DISPLAY 0.680851 (-3500 700);
PAINT MONO (-3500 700);
DISPLAY INVISIBLE (-3500 700);
FORCEADD GND..1
(-3450 225);
FORCEPROP 3 LASTPIN (-3450 275) SIG_NAME GND\g
J 0
(-3440 285);
DISPLAY 0.659574 (-3440 285);
PAINT MONO (-3440 285);
DISPLAY INVISIBLE (-3440 285);
FORCEPROP 1 LAST VOLTAGE 0.0V
J 0
(-3495 182);
DISPLAY 0.340426 (-3495 182);
PAINT SKYBLUE (-3495 182);
DISPLAY INVISIBLE (-3495 182);
FORCEPROP 1 LAST SIZE 1B
J 0
(-3375 175);
DISPLAY 0.872340 (-3375 175);
PAINT AQUA (-3375 175);
DISPLAY INVISIBLE (-3375 175);
FORCEPROP 2 LAST CDS_LIB mstr_symbols
J 0
(-3450 225);
PAINT MONO (-3450 225);
DISPLAY INVISIBLE (-3450 225);
FORCEPROP 1 LAST PATH I202
J 0
(-3375 225);
DISPLAY 0.872340 (-3375 225);
PAINT AQUA (-3375 225);
DISPLAY INVISIBLE (-3375 225);
FORCEPROP 1 LAST BODY_TYPE PLUMBING
J 0
(-3495 182);
DISPLAY 0.340426 (-3495 182);
PAINT GREEN (-3495 182);
DISPLAY INVISIBLE (-3495 182);
FORCEPROP 1 LAST HDL_POWER GND
J 0
(-3450 375);
DISPLAY 0.872340 (-3450 375);
PAINT GREEN (-3450 375);
DISPLAY INVISIBLE (-3450 375);
FORCEADD FET_N..8
(-3500 1300);
FORCEPROP 1 LAST LOCATION Q1D2
J 0
(-3300 1300);
DISPLAY 0.617021 (-3300 1300);
PAINT AQUA (-3300 1300);
FORCEPROP 1 LASTPIN (-3700 1200) $PN 1
J 2
(-3697 1215);
DISPLAY 0.617021 (-3697 1215);
PAINT WHITE (-3697 1215);
FORCEPROP 1 LAST MATERIAL FET
J 0
(-3300 1200);
DISPLAY 0.617021 (-3300 1200);
PAINT SKYBLUE (-3300 1200);
FORCEPROP 1 LASTPIN (-3500 1100) $PN 2
J 2
(-3442 1100);
DISPLAY 0.617021 (-3442 1100);
PAINT WHITE (-3442 1100);
FORCEPROP 1 LAST VALUE 2N7002
J 0
(-3300 1250);
DISPLAY 0.617021 (-3300 1250);
PAINT SKYBLUE (-3300 1250);
FORCEPROP 1 LAST PART_NUMBER C79254-001
J 0
(-3300 1100);
DISPLAY 0.617021 (-3300 1100);
PAINT BLUE (-3300 1100);
FORCEPROP 1 LASTPIN (-3500 1500) $PN 3
J 2
(-3447 1465);
DISPLAY 0.617021 (-3447 1465);
PAINT WHITE (-3447 1465);
FORCEPROP 2 LAST CDS_LIB mstr_discrete
J 0
(-3500 1300);
PAINT ORANGE (-3500 1300);
DISPLAY INVISIBLE (-3500 1300);
FORCEPROP 2 LAST CDS_LOCATION Q1D2
J 0
(-3300 1300);
DISPLAY 0.617021 (-3300 1300);
PAINT AQUA (-3300 1300);
DISPLAY INVISIBLE (-3300 1300);
FORCEPROP 2 LAST SEC 1
J 0
(-3300 1400);
DISPLAY 0.680851 (-3300 1400);
PAINT MONO (-3300 1400);
DISPLAY INVISIBLE (-3300 1400);
FORCEPROP 2 LAST SEC_TYPE SOT23LF
J 0
(-3300 1400);
DISPLAY 1.021277 (-3300 1400);
PAINT ORANGE (-3300 1400);
DISPLAY INVISIBLE (-3300 1400);
FORCEPROP 0 LAST ROOM HOT_SWAP
J 0
(-3300 1400);
DISPLAY 1.021277 (-3300 1400);
PAINT ORANGE (-3300 1400);
DISPLAY INVISIBLE (-3300 1400);
FORCEPROP 1 LAST PACK_TYPE SOT23LF
J 0
(-3300 1150);
DISPLAY 0.978723 (-3300 1150);
PAINT SKYBLUE (-3300 1150);
DISPLAY INVISIBLE (-3300 1150);
FORCEPROP 1 LAST PATH I203
J 0
(-3300 1350);
DISPLAY 0.978723 (-3300 1350);
PAINT BLUE (-3300 1350);
DISPLAY INVISIBLE (-3300 1350);
FORCEADD RES..2
(-3500 1750);
FORCEPROP 1 LASTPIN (-3500 1850) $PN 1
J 0
(-3495 1812);
DISPLAY 0.617021 (-3495 1812);
PAINT ORANGE (-3495 1812);
FORCEPROP 1 LAST TOLERANCE 1%
J 0
(-3455 1775);
DISPLAY 0.617021 (-3455 1775);
PAINT SKYBLUE (-3455 1775);
FORCEPROP 1 LASTPIN (-3500 1650) $PN 2
J 0
(-3495 1660);
DISPLAY 0.617021 (-3495 1660);
PAINT ORANGE (-3495 1660);
FORCEPROP 1 LAST MATERIAL CHIP
J 0
(-3460 1675);
DISPLAY 0.617021 (-3460 1675);
PAINT SKYBLUE (-3460 1675);
FORCEPROP 1 LAST VALUE 4.75K
J 0
(-3455 1825);
DISPLAY 0.617021 (-3455 1825);
PAINT SKYBLUE (-3455 1825);
FORCEPROP 1 LAST LOCATION R1D21
J 0
(-3455 1875);
DISPLAY 0.617021 (-3455 1875);
PAINT AQUA (-3455 1875);
FORCEPROP 1 LAST PACK_TYPE 0402
J 0
(-3460 1575);
DISPLAY 0.617021 (-3460 1575);
PAINT SKYBLUE (-3460 1575);
FORCEPROP 1 LAST WATTAGE 1/16W
J 0
(-3460 1725);
DISPLAY 0.617021 (-3460 1725);
PAINT SKYBLUE (-3460 1725);
FORCEPROP 1 LAST PART_NUMBER G21796-072
J 0
(-3460 1625);
DISPLAY 0.617021 (-3460 1625);
PAINT BLUE (-3460 1625);
FORCEPROP 2 LAST CDS_LIB mstr_discrete
J 0
(-3500 1750);
PAINT ORANGE (-3500 1750);
DISPLAY INVISIBLE (-3500 1750);
FORCEPROP 2 LAST CDS_LOCATION R1D21
J 0
(-3455 1875);
DISPLAY 0.617021 (-3455 1875);
PAINT AQUA (-3455 1875);
DISPLAY INVISIBLE (-3455 1875);
FORCEPROP 2 LAST SEC_TYPE 0402
J 0
(-3450 1975);
DISPLAY 1.021277 (-3450 1975);
PAINT ORANGE (-3450 1975);
DISPLAY INVISIBLE (-3450 1975);
FORCEPROP 2 LAST SEC 1
J 0
(-3450 1975);
DISPLAY 0.680851 (-3450 1975);
PAINT MONO (-3450 1975);
DISPLAY INVISIBLE (-3450 1975);
FORCEPROP 1 LAST PATH I204
J 0
(-3450 1925);
DISPLAY 0.978723 (-3450 1925);
PAINT WHITE (-3450 1925);
DISPLAY INVISIBLE (-3450 1925);
FORCEPROP 0 LAST ROOM HOT_SWAP
J 0
(-3450 1975);
DISPLAY 1.021277 (-3450 1975);
PAINT ORANGE (-3450 1975);
DISPLAY INVISIBLE (-3450 1975);
FORCEADD P3V3_STBY..1
(-3500 1950);
FORCEPROP 3 LASTPIN (-3500 1900) SIG_NAME P3V3_STBY\g
J 0
(-3490 1910);
DISPLAY 0.659574 (-3490 1910);
PAINT MONO (-3490 1910);
DISPLAY INVISIBLE (-3490 1910);
FORCEPROP 1 LAST VOLTAGE 3.3V
J 0
(-3545 1907);
DISPLAY 0.340426 (-3545 1907);
PAINT SKYBLUE (-3545 1907);
DISPLAY INVISIBLE (-3545 1907);
FORCEPROP 2 LAST CDS_LIB mstr_symbols
J 0
(-3500 1950);
PAINT ORANGE (-3500 1950);
DISPLAY INVISIBLE (-3500 1950);
FORCEPROP 1 LAST SIZE 1B
J 0
(-3455 1972);
DISPLAY 0.340426 (-3455 1972);
PAINT GREEN (-3455 1972);
DISPLAY INVISIBLE (-3455 1972);
FORCEPROP 1 LAST PATH I205
J 0
(-3455 1952);
DISPLAY 0.340426 (-3455 1952);
PAINT GREEN (-3455 1952);
DISPLAY INVISIBLE (-3455 1952);
FORCEPROP 1 LAST BODY_TYPE PLUMBING
J 0
(-3545 1907);
DISPLAY 0.340426 (-3545 1907);
PAINT GREEN (-3545 1907);
DISPLAY INVISIBLE (-3545 1907);
FORCEPROP 1 LAST HDL_POWER P3V3_STBY
J 0
(-3800 1825);
DISPLAY 0.872340 (-3800 1825);
PAINT ORANGE (-3800 1825);
DISPLAY INVISIBLE (-3800 1825);
FORCEADD GND..1
(-3500 925);
FORCEPROP 3 LASTPIN (-3500 975) SIG_NAME GND\g
J 0
(-3490 985);
DISPLAY 0.659574 (-3490 985);
PAINT MONO (-3490 985);
DISPLAY INVISIBLE (-3490 985);
FORCEPROP 2 LAST CDS_LIB mstr_symbols
J 0
(-3500 925);
PAINT ORANGE (-3500 925);
DISPLAY INVISIBLE (-3500 925);
FORCEPROP 1 LAST PATH I206
J 0
(-3425 925);
DISPLAY 0.872340 (-3425 925);
PAINT AQUA (-3425 925);
DISPLAY INVISIBLE (-3425 925);
FORCEPROP 1 LAST SIZE 1B
J 0
(-3425 875);
DISPLAY 0.872340 (-3425 875);
PAINT AQUA (-3425 875);
DISPLAY INVISIBLE (-3425 875);
FORCEPROP 1 LAST VOLTAGE 0.0V
J 0
(-3545 882);
DISPLAY 0.340426 (-3545 882);
PAINT SKYBLUE (-3545 882);
DISPLAY INVISIBLE (-3545 882);
FORCEPROP 1 LAST BODY_TYPE PLUMBING
J 0
(-3545 882);
DISPLAY 0.340426 (-3545 882);
PAINT GREEN (-3545 882);
DISPLAY INVISIBLE (-3545 882);
FORCEPROP 1 LAST HDL_POWER GND
J 0
(-3500 1075);
DISPLAY 0.872340 (-3500 1075);
PAINT GREEN (-3500 1075);
DISPLAY INVISIBLE (-3500 1075);
FORCEADD OFFPAGE..1
(-4375 1200);
FORCEPROP 2 LAST $XR2 145 
J 0
(-4867 1200);
DISPLAY 0.638298 (-4867 1200);
PAINT MONO (-4867 1200);
FORCEPROP 2 LAST $XR1 126 
J 0
(-4747 1200);
DISPLAY 0.638298 (-4747 1200);
PAINT MONO (-4747 1200);
FORCEPROP 2 LAST $XR0 120 
J 0
(-4627 1200);
DISPLAY 0.638298 (-4627 1200);
PAINT MONO (-4627 1200);
FORCEPROP 2 LAST PATH I207
J 0
(-4325 1275);
DISPLAY 1.021277 (-4325 1275);
PAINT ORANGE (-4325 1275);
DISPLAY INVISIBLE (-4325 1275);
FORCEPROP 2 LAST CDS_LIB mstr_standard
J 0
(-4375 1200);
PAINT ORANGE (-4375 1200);
DISPLAY INVISIBLE (-4375 1200);
FORCEPROP 1 LAST OFFPAGE TRUE
J 0
(-4050 1075);
DISPLAY 0.872340 (-4050 1075);
PAINT GREEN (-4050 1075);
DISPLAY INVISIBLE (-4050 1075);
FORCEPROP 1 LAST COMMENT_BODY TRUE
J 0
(-4250 1100);
DISPLAY 0.872340 (-4250 1100);
PAINT GREEN (-4250 1100);
DISPLAY INVISIBLE (-4250 1100);
FORCEADD RES..2
(1750 225);
FORCEPROP 1 LASTPIN (1750 125) $PN 2
J 0
(1755 135);
DISPLAY 0.617021 (1755 135);
PAINT ORANGE (1755 135);
FORCEPROP 1 LASTPIN (1750 325) $PN 1
J 0
(1755 287);
DISPLAY 0.617021 (1755 287);
PAINT ORANGE (1755 287);
FORCEPROP 1 LAST MATERIAL CHIP
J 0
(1790 150);
DISPLAY 0.617021 (1790 150);
PAINT SKYBLUE (1790 150);
FORCEPROP 1 LAST PACK_TYPE 0402
J 0
(1790 50);
DISPLAY 0.617021 (1790 50);
PAINT SKYBLUE (1790 50);
FORCEPROP 1 LAST PART_NUMBER G21796-344
J 0
(1790 100);
DISPLAY 0.617021 (1790 100);
PAINT BLUE (1790 100);
FORCEPROP 1 LAST TOLERANCE 1%
J 0
(1795 250);
DISPLAY 0.617021 (1795 250);
PAINT SKYBLUE (1795 250);
FORCEPROP 1 LAST WATTAGE 1/16W
J 0
(1790 200);
DISPLAY 0.617021 (1790 200);
PAINT SKYBLUE (1790 200);
FORCEPROP 1 LAST LOCATION R9P4
J 0
(1795 350);
DISPLAY 0.617021 (1795 350);
PAINT AQUA (1795 350);
FORCEPROP 1 LAST VALUE 2.7K
J 0
(1795 300);
DISPLAY 0.617021 (1795 300);
PAINT SKYBLUE (1795 300);
FORCEPROP 2 LAST CDS_LIB mstr_discrete
J 0
(1750 225);
PAINT MONO (1750 225);
DISPLAY INVISIBLE (1750 225);
FORCEPROP 2 LAST ROOM HOT_SWAP
J 0
(1800 400);
PAINT MONO (1800 400);
DISPLAY INVISIBLE (1800 400);
FORCEPROP 1 LAST PATH I210
J 0
(1800 400);
DISPLAY 0.978723 (1800 400);
PAINT WHITE (1800 400);
DISPLAY INVISIBLE (1800 400);
FORCEPROP 2 LAST CDS_LOCATION R9P4
J 0
(1795 350);
DISPLAY 0.617021 (1795 350);
PAINT AQUA (1795 350);
DISPLAY INVISIBLE (1795 350);
FORCEPROP 2 LAST SEC 1
J 0
(1800 450);
DISPLAY 0.680851 (1800 450);
PAINT MONO (1800 450);
DISPLAY INVISIBLE (1800 450);
FORCEPROP 2 LAST SEC_TYPE 0402
J 0
(1800 450);
DISPLAY 1.021277 (1800 450);
PAINT ORANGE (1800 450);
DISPLAY INVISIBLE (1800 450);
FORCEADD P3V3_STBY..1
(1750 450);
FORCEPROP 3 LASTPIN (1750 400) SIG_NAME P3V3_STBY\g
J 0
(1760 410);
DISPLAY 0.659574 (1760 410);
PAINT MONO (1760 410);
DISPLAY INVISIBLE (1760 410);
FORCEPROP 2 LAST CDS_LIB mstr_symbols
J 0
(1750 450);
PAINT ORANGE (1750 450);
DISPLAY INVISIBLE (1750 450);
FORCEPROP 1 LAST PATH I211
J 0
(1795 452);
DISPLAY 0.340426 (1795 452);
PAINT GREEN (1795 452);
DISPLAY INVISIBLE (1795 452);
FORCEPROP 1 LAST SIZE 1B
J 0
(1795 472);
DISPLAY 0.340426 (1795 472);
PAINT GREEN (1795 472);
DISPLAY INVISIBLE (1795 472);
FORCEPROP 1 LAST VOLTAGE +3.3V
J 0
(1950 600);
DISPLAY 1.021277 (1950 600);
PAINT SKYBLUE (1950 600);
DISPLAY INVISIBLE (1950 600);
FORCEPROP 1 LAST BODY_TYPE PLUMBING
J 0
(1705 407);
DISPLAY 0.340426 (1705 407);
PAINT GREEN (1705 407);
DISPLAY INVISIBLE (1705 407);
FORCEPROP 1 LAST HDL_POWER P3V3_STBY
J 0
(1450 325);
DISPLAY 0.872340 (1450 325);
PAINT ORANGE (1450 325);
DISPLAY INVISIBLE (1450 325);
FORCEADD DIODE..1
R 2
(1000 675);
FORCEPROP 1 LAST PART_NUMBER C73510-001
J 2
(1025 775);
DISPLAY 0.617021 (1025 775);
PAINT BLUE (1025 775);
FORCEPROP 1 LASTPIN (900 675) $PN 1
J 2
(935 685);
DISPLAY 0.617021 (935 685);
PAINT AQUA (935 685);
FORCEPROP 1 LAST PACK_TYPE SMLF
J 2
(1225 485);
DISPLAY 0.617021 (1225 485);
PAINT SKYBLUE (1225 485);
FORCEPROP 1 LAST MATERIAL IC
J 2
(1025 497);
DISPLAY 0.617021 (1025 497);
PAINT SKYBLUE (1025 497);
FORCEPROP 1 LAST LOCATION CR9P2
J 2
(1027 831);
DISPLAY 0.617021 (1027 831);
PAINT AQUA (1027 831);
FORCEPROP 1 LASTPIN (1100 675) $PN 2
J 0
(1065 685);
DISPLAY 0.617021 (1065 685);
PAINT AQUA (1065 685);
FORCEPROP 1 LAST VALUE BAT54WS
J 2
(1025 550);
DISPLAY 0.617021 (1025 550);
PAINT SKYBLUE (1025 550);
FORCEPROP 1 LAST PATH I213
J 2
(1020 885);
DISPLAY 0.978723 (1020 885);
PAINT PINK (1020 885);
DISPLAY INVISIBLE (1020 885);
FORCEPROP 2 LAST CDS_LOCATION CR9P2
J 2
(1027 831);
DISPLAY 0.617021 (1027 831);
PAINT AQUA (1027 831);
DISPLAY INVISIBLE (1027 831);
FORCEPROP 2 LAST SEC 1
J 0
(1025 950);
DISPLAY 0.680851 (1025 950);
PAINT MONO (1025 950);
DISPLAY INVISIBLE (1025 950);
FORCEPROP 2 LAST SEC_TYPE SMLF
J 0
(1025 950);
DISPLAY 1.021277 (1025 950);
PAINT ORANGE (1025 950);
DISPLAY INVISIBLE (1025 950);
FORCEPROP 2 LAST CDS_LIB mstr_discrete
J 2
(1000 675);
PAINT ORANGE (1000 675);
DISPLAY INVISIBLE (1000 675);
FORCEADD DIODE..1
R 2
(1050 175);
FORCEPROP 1 LAST LOCATION CR9P1
J 2
(1077 331);
DISPLAY 0.617021 (1077 331);
PAINT AQUA (1077 331);
FORCEPROP 1 LASTPIN (950 175) $PN 1
J 2
(985 185);
DISPLAY 0.617021 (985 185);
PAINT AQUA (985 185);
FORCEPROP 1 LAST VALUE BAT54WS
J 2
(1075 50);
DISPLAY 0.617021 (1075 50);
PAINT SKYBLUE (1075 50);
FORCEPROP 1 LASTPIN (1150 175) $PN 2
J 0
(1115 185);
DISPLAY 0.617021 (1115 185);
PAINT AQUA (1115 185);
FORCEPROP 0 LAST POP NOPOP
J 0
(1175 125);
DISPLAY 0.638298 (1175 125);
PAINT RED (1175 125);
FORCEPROP 1 LAST PACK_TYPE SMLF
J 2
(1275 60);
DISPLAY 0.617021 (1275 60);
PAINT SKYBLUE (1275 60);
FORCEPROP 1 LAST MATERIAL IC
J 2
(1375 47);
DISPLAY 0.617021 (1375 47);
PAINT SKYBLUE (1375 47);
FORCEPROP 1 LAST PART_NUMBER C73510-001
J 2
(1075 275);
DISPLAY 0.617021 (1075 275);
PAINT BLUE (1075 275);
FORCEPROP 1 LAST PATH I214
J 2
(1070 385);
DISPLAY 0.978723 (1070 385);
PAINT PINK (1070 385);
DISPLAY INVISIBLE (1070 385);
FORCEPROP 2 LAST CDS_LOCATION CR9P1
J 2
(1077 331);
DISPLAY 0.617021 (1077 331);
PAINT AQUA (1077 331);
DISPLAY INVISIBLE (1077 331);
FORCEPROP 2 LAST SEC 1
J 0
(1075 450);
DISPLAY 0.680851 (1075 450);
PAINT MONO (1075 450);
DISPLAY INVISIBLE (1075 450);
FORCEPROP 2 LAST SEC_TYPE SMLF
J 0
(1075 450);
DISPLAY 1.021277 (1075 450);
PAINT ORANGE (1075 450);
DISPLAY INVISIBLE (1075 450);
FORCEPROP 2 LAST CDS_LIB mstr_discrete
J 2
(1050 175);
PAINT ORANGE (1050 175);
DISPLAY INVISIBLE (1050 175);
FORCEADD RES..2
(1500 1125);
FORCEPROP 1 LASTPIN (1500 1025) $PN 2
J 0
(1505 1035);
DISPLAY 0.617021 (1505 1035);
PAINT ORANGE (1505 1035);
FORCEPROP 1 LASTPIN (1500 1225) $PN 1
J 0
(1505 1187);
DISPLAY 0.617021 (1505 1187);
PAINT ORANGE (1505 1187);
FORCEPROP 1 LAST MATERIAL CHIP
J 0
(1540 1050);
DISPLAY 0.617021 (1540 1050);
PAINT SKYBLUE (1540 1050);
FORCEPROP 1 LAST TOLERANCE 1%
J 0
(1545 1150);
DISPLAY 0.617021 (1545 1150);
PAINT SKYBLUE (1545 1150);
FORCEPROP 1 LAST VALUE 10.0K
J 0
(1545 1200);
DISPLAY 0.617021 (1545 1200);
PAINT SKYBLUE (1545 1200);
FORCEPROP 1 LAST LOCATION R9P5
J 0
(1545 1250);
DISPLAY 0.617021 (1545 1250);
PAINT AQUA (1545 1250);
FORCEPROP 1 LAST PART_NUMBER G21796-016
J 0
(1540 1000);
DISPLAY 0.617021 (1540 1000);
PAINT BLUE (1540 1000);
FORCEPROP 1 LAST WATTAGE 1/16W
J 0
(1540 1100);
DISPLAY 0.617021 (1540 1100);
PAINT SKYBLUE (1540 1100);
FORCEPROP 1 LAST PACK_TYPE 0402
J 0
(1540 950);
DISPLAY 0.617021 (1540 950);
PAINT SKYBLUE (1540 950);
FORCEPROP 2 LAST CDS_LIB mstr_discrete
J 0
(1500 1125);
PAINT ORANGE (1500 1125);
DISPLAY INVISIBLE (1500 1125);
FORCEPROP 2 LAST ROOM HOT_SWAP
J 0
(1550 1300);
PAINT MONO (1550 1300);
DISPLAY INVISIBLE (1550 1300);
FORCEPROP 1 LAST PATH I215
J 0
(1550 1300);
DISPLAY 0.978723 (1550 1300);
PAINT WHITE (1550 1300);
DISPLAY INVISIBLE (1550 1300);
FORCEPROP 2 LAST CDS_LOCATION R9P5
J 0
(1545 1250);
DISPLAY 0.617021 (1545 1250);
PAINT AQUA (1545 1250);
DISPLAY INVISIBLE (1545 1250);
FORCEPROP 2 LAST SEC 1
J 0
(1550 1350);
DISPLAY 0.680851 (1550 1350);
PAINT MONO (1550 1350);
DISPLAY INVISIBLE (1550 1350);
FORCEPROP 2 LAST SEC_TYPE 0402
J 0
(1550 1350);
DISPLAY 1.021277 (1550 1350);
PAINT ORANGE (1550 1350);
DISPLAY INVISIBLE (1550 1350);
FORCEADD P3V3_STBY..1
(1500 1400);
FORCEPROP 3 LASTPIN (1500 1350) SIG_NAME P3V3_STBY\g
J 0
(1510 1360);
DISPLAY 0.659574 (1510 1360);
PAINT MONO (1510 1360);
DISPLAY INVISIBLE (1510 1360);
FORCEPROP 2 LAST CDS_LIB mstr_symbols
J 0
(1500 1400);
PAINT ORANGE (1500 1400);
DISPLAY INVISIBLE (1500 1400);
FORCEPROP 1 LAST PATH I216
J 0
(1545 1402);
DISPLAY 0.340426 (1545 1402);
PAINT GREEN (1545 1402);
DISPLAY INVISIBLE (1545 1402);
FORCEPROP 1 LAST SIZE 1B
J 0
(1545 1422);
DISPLAY 0.340426 (1545 1422);
PAINT GREEN (1545 1422);
DISPLAY INVISIBLE (1545 1422);
FORCEPROP 1 LAST VOLTAGE +3.3V
J 0
(1700 1550);
DISPLAY 1.021277 (1700 1550);
PAINT SKYBLUE (1700 1550);
DISPLAY INVISIBLE (1700 1550);
FORCEPROP 1 LAST BODY_TYPE PLUMBING
J 0
(1455 1357);
DISPLAY 0.340426 (1455 1357);
PAINT GREEN (1455 1357);
DISPLAY INVISIBLE (1455 1357);
FORCEPROP 1 LAST HDL_POWER P3V3_STBY
J 0
(1200 1275);
DISPLAY 0.872340 (1200 1275);
PAINT ORANGE (1200 1275);
DISPLAY INVISIBLE (1200 1275);
FORCEADD AGND0..1
(-4400 -650);
FORCEPROP 3 LASTPIN (-4400 -600) SIG_NAME AGND_HSC\g
J 0
(-4390 -590);
DISPLAY 0.659574 (-4390 -590);
PAINT MONO (-4390 -590);
DISPLAY INVISIBLE (-4390 -590);
FORCEPROP 1 LAST HDL_POWER AGND_HSC
J 1
(-4400 -700);
DISPLAY 0.617021 (-4400 -700);
PAINT GREEN (-4400 -700);
FORCEPROP 1 LAST VOLTAGE 0
J 0
(-4400 -650);
PAINT SKYBLUE (-4400 -650);
DISPLAY INVISIBLE (-4400 -650);
FORCEPROP 2 LAST BOM_COST MIO_VRD_MAIN
J 0
(-4375 -675);
PAINT ORANGE (-4375 -675);
DISPLAY INVISIBLE (-4375 -675);
FORCEPROP 2 LAST CDS_LIB mstr_symbols
J 0
(-4400 -650);
PAINT ORANGE (-4400 -650);
DISPLAY INVISIBLE (-4400 -650);
FORCEPROP 2 LAST ROOM VR_P3V3
J 0
(-4425 -675);
PAINT ORANGE (-4425 -675);
DISPLAY INVISIBLE (-4425 -675);
FORCEPROP 1 LAST PATH I217
J 0
(-4325 -650);
DISPLAY 0.872340 (-4325 -650);
PAINT AQUA (-4325 -650);
DISPLAY INVISIBLE (-4325 -650);
FORCEPROP 1 LAST BODY_TYPE PLUMBING
J 0
(-4445 -693);
DISPLAY 0.340426 (-4445 -693);
PAINT GREEN (-4445 -693);
DISPLAY INVISIBLE (-4445 -693);
FORCEADD RES..2
(-3950 -475);
FORCEPROP 1 LASTPIN (-3950 -575) $PN 2
J 0
(-3945 -565);
DISPLAY 0.617021 (-3945 -565);
PAINT ORANGE (-3945 -565);
FORCEPROP 1 LAST MATERIAL CHIP
J 0
(-3910 -550);
DISPLAY 0.617021 (-3910 -550);
PAINT SKYBLUE (-3910 -550);
FORCEPROP 1 LAST PACK_TYPE 0402
J 0
(-3910 -650);
DISPLAY 0.617021 (-3910 -650);
PAINT SKYBLUE (-3910 -650);
FORCEPROP 1 LAST PART_NUMBER G21796-013
J 0
(-3910 -600);
DISPLAY 0.617021 (-3910 -600);
PAINT BLUE (-3910 -600);
FORCEPROP 1 LASTPIN (-3950 -375) $PN 1
J 0
(-3945 -413);
DISPLAY 0.617021 (-3945 -413);
PAINT ORANGE (-3945 -413);
FORCEPROP 1 LAST TOLERANCE 1%
J 0
(-3905 -450);
DISPLAY 0.617021 (-3905 -450);
PAINT SKYBLUE (-3905 -450);
FORCEPROP 1 LAST WATTAGE 1/16W
J 0
(-3910 -500);
DISPLAY 0.617021 (-3910 -500);
PAINT SKYBLUE (-3910 -500);
FORCEPROP 1 LAST VALUE 4.99K
J 0
(-3905 -400);
DISPLAY 0.617021 (-3905 -400);
PAINT SKYBLUE (-3905 -400);
FORCEPROP 1 LAST LOCATION R9P12
J 0
(-3905 -350);
DISPLAY 0.617021 (-3905 -350);
PAINT AQUA (-3905 -350);
FORCEPROP 2 LAST ROOM HOT_SWAP
J 0
(-3900 -300);
PAINT MONO (-3900 -300);
DISPLAY INVISIBLE (-3900 -300);
FORCEPROP 2 LAST CDS_LIB mstr_discrete
J 0
(-3950 -475);
PAINT ORANGE (-3950 -475);
DISPLAY INVISIBLE (-3950 -475);
FORCEPROP 2 LAST CDS_LOCATION R9P12
J 0
(-3905 -350);
DISPLAY 0.617021 (-3905 -350);
PAINT AQUA (-3905 -350);
DISPLAY INVISIBLE (-3905 -350);
FORCEPROP 1 LAST PATH I218
J 0
(-3900 -300);
DISPLAY 0.978723 (-3900 -300);
PAINT WHITE (-3900 -300);
DISPLAY INVISIBLE (-3900 -300);
FORCEPROP 2 LAST SEC 1
J 0
(-3900 -250);
DISPLAY 0.680851 (-3900 -250);
PAINT MONO (-3900 -250);
DISPLAY INVISIBLE (-3900 -250);
FORCEPROP 2 LAST SEC_TYPE 0402
J 0
(-3900 -250);
DISPLAY 1.021277 (-3900 -250);
PAINT ORANGE (-3900 -250);
DISPLAY INVISIBLE (-3900 -250);
FORCEADD AGND0..1
(-3950 -675);
FORCEPROP 3 LASTPIN (-3950 -625) SIG_NAME AGND_HSC\g
J 0
(-3940 -615);
DISPLAY 0.659574 (-3940 -615);
PAINT MONO (-3940 -615);
DISPLAY INVISIBLE (-3940 -615);
FORCEPROP 1 LAST HDL_POWER AGND_HSC
J 1
(-3950 -725);
DISPLAY 0.617021 (-3950 -725);
PAINT GREEN (-3950 -725);
FORCEPROP 2 LAST ROOM VR_P3V3
J 0
(-3975 -700);
PAINT ORANGE (-3975 -700);
DISPLAY INVISIBLE (-3975 -700);
FORCEPROP 2 LAST BOM_COST MIO_VRD_MAIN
J 0
(-3925 -700);
PAINT ORANGE (-3925 -700);
DISPLAY INVISIBLE (-3925 -700);
FORCEPROP 1 LAST VOLTAGE 0
J 0
(-3950 -675);
PAINT SKYBLUE (-3950 -675);
DISPLAY INVISIBLE (-3950 -675);
FORCEPROP 1 LAST PATH I219
J 0
(-3875 -675);
DISPLAY 0.872340 (-3875 -675);
PAINT AQUA (-3875 -675);
DISPLAY INVISIBLE (-3875 -675);
FORCEPROP 2 LAST CDS_LIB mstr_symbols
J 0
(-3950 -675);
PAINT ORANGE (-3950 -675);
DISPLAY INVISIBLE (-3950 -675);
FORCEPROP 1 LAST BODY_TYPE PLUMBING
J 0
(-3995 -718);
DISPLAY 0.340426 (-3995 -718);
PAINT GREEN (-3995 -718);
DISPLAY INVISIBLE (-3995 -718);
FORCEADD DIODE..1
R 1
(2750 3275);
FORCEPROP 1 LASTPIN (2750 3175) $PN 2
R 1
J 2
(2740 3210);
DISPLAY 0.617021 (2740 3210);
PAINT AQUA (2740 3210);
FORCEPROP 1 LAST LOCATION CR1F5
R 1
J 0
(2594 3248);
DISPLAY 0.617021 (2594 3248);
PAINT AQUA (2594 3248);
FORCEPROP 1 LASTPIN (2750 3375) $PN 1
R 1
J 0
(2740 3340);
DISPLAY 0.617021 (2740 3340);
PAINT AQUA (2740 3340);
FORCEPROP 1 LAST PACK_TYPE SM
R 1
J 0
(2990 3250);
DISPLAY 0.617021 (2990 3250);
PAINT SKYBLUE (2990 3250);
FORCEPROP 1 LAST VALUE MBRS340T3G
R 1
J 0
(2875 3250);
DISPLAY 0.617021 (2875 3250);
PAINT SKYBLUE (2875 3250);
FORCEPROP 1 LAST MATERIAL EMPTY
R 1
J 0
(2928 3250);
DISPLAY 0.617021 (2928 3250);
PAINT RED (2928 3250);
FORCEPROP 1 LAST PART_NUMBER C81983-002
R 1
J 0
(2650 3200);
DISPLAY 0.617021 (2650 3200);
PAINT BLUE (2650 3200);
FORCEPROP 1 LAST PATH I220
R 1
J 0
(2540 3255);
DISPLAY 0.978723 (2540 3255);
PAINT PINK (2540 3255);
DISPLAY INVISIBLE (2540 3255);
FORCEPROP 2 LAST CDS_LIB mstr_discrete
J 0
(2750 3275);
PAINT ORANGE (2750 3275);
DISPLAY INVISIBLE (2750 3275);
FORCEPROP 2 LAST SEC_TYPE SM
J 0
(2800 3400);
DISPLAY 1.021277 (2800 3400);
PAINT ORANGE (2800 3400);
DISPLAY INVISIBLE (2800 3400);
FORCEPROP 2 LAST SEC 1
J 0
(2800 3400);
DISPLAY 0.680851 (2800 3400);
PAINT MONO (2800 3400);
DISPLAY INVISIBLE (2800 3400);
FORCEADD GND..1
(2750 3000);
FORCEPROP 3 LASTPIN (2750 3050) SIG_NAME GND\g
J 0
(2760 3060);
DISPLAY 0.659574 (2760 3060);
PAINT MONO (2760 3060);
DISPLAY INVISIBLE (2760 3060);
FORCEPROP 1 LAST PATH I221
J 0
(2825 3000);
DISPLAY 0.872340 (2825 3000);
PAINT AQUA (2825 3000);
DISPLAY INVISIBLE (2825 3000);
FORCEPROP 2 LAST CDS_LIB mstr_symbols
J 0
(2750 3000);
PAINT ORANGE (2750 3000);
DISPLAY INVISIBLE (2750 3000);
FORCEPROP 1 LAST SIZE 1B
J 0
(2825 2950);
DISPLAY 0.872340 (2825 2950);
PAINT AQUA (2825 2950);
DISPLAY INVISIBLE (2825 2950);
FORCEPROP 1 LAST VOLTAGE 0.0V
J 0
(2705 2957);
DISPLAY 0.340426 (2705 2957);
PAINT SKYBLUE (2705 2957);
DISPLAY INVISIBLE (2705 2957);
FORCEPROP 1 LAST BODY_TYPE PLUMBING
J 0
(2705 2957);
DISPLAY 0.340426 (2705 2957);
PAINT GREEN (2705 2957);
DISPLAY INVISIBLE (2705 2957);
FORCEPROP 1 LAST HDL_POWER GND
J 0
(2750 3150);
DISPLAY 0.872340 (2750 3150);
PAINT GREEN (2750 3150);
DISPLAY INVISIBLE (2750 3150);
FORCEADD RES..2
R 2
(-3950 200);
FORCEPROP 1 LAST WATTAGE 1/16W
J 2
(-3990 175);
DISPLAY 0.617021 (-3990 175);
PAINT SKYBLUE (-3990 175);
FORCEPROP 1 LAST MATERIAL CHIP
J 2
(-3990 125);
DISPLAY 0.617021 (-3990 125);
PAINT SKYBLUE (-3990 125);
FORCEPROP 1 LAST PACK_TYPE 0402
J 2
(-3990 25);
DISPLAY 0.617021 (-3990 25);
PAINT SKYBLUE (-3990 25);
FORCEPROP 1 LAST VALUE 100.0K
J 2
(-3995 275);
DISPLAY 0.617021 (-3995 275);
PAINT SKYBLUE (-3995 275);
FORCEPROP 1 LAST PART_NUMBER G21796-010
J 2
(-3990 75);
DISPLAY 0.617021 (-3990 75);
PAINT BLUE (-3990 75);
FORCEPROP 1 LAST TOLERANCE 1%
J 2
(-3995 225);
DISPLAY 0.617021 (-3995 225);
PAINT SKYBLUE (-3995 225);
FORCEPROP 1 LAST LOCATION R9P33
J 2
(-3995 325);
DISPLAY 0.617021 (-3995 325);
PAINT AQUA (-3995 325);
FORCEPROP 1 LASTPIN (-3950 100) $PN 2
J 2
(-3955 110);
DISPLAY 0.787234 (-3955 110);
PAINT ORANGE (-3955 110);
DISPLAY INVISIBLE (-3955 110);
FORCEPROP 2 LAST CDS_LIB mstr_discrete
J 2
(-3950 200);
PAINT ORANGE (-3950 200);
DISPLAY INVISIBLE (-3950 200);
FORCEPROP 1 LASTPIN (-3950 300) $PN 1
J 2
(-3955 262);
DISPLAY 0.787234 (-3955 262);
PAINT ORANGE (-3955 262);
DISPLAY INVISIBLE (-3955 262);
FORCEPROP 2 LAST ROOM HOT_SWAP
J 2
(-4000 375);
PAINT MONO (-4000 375);
DISPLAY INVISIBLE (-4000 375);
FORCEPROP 1 LAST PATH I222
J 2
(-4000 375);
DISPLAY 0.978723 (-4000 375);
PAINT WHITE (-4000 375);
DISPLAY INVISIBLE (-4000 375);
FORCEPROP 2 LAST $SEC 1
J 0
(-4000 425);
PAINT MONO (-4000 425);
DISPLAY INVISIBLE (-4000 425);
FORCEPROP 2 LAST CDS_SEC 1
J 0
(-4000 425);
PAINT MONO (-4000 425);
DISPLAY INVISIBLE (-4000 425);
FORCEADD P12V_STBY..1
(-3950 700);
FORCEPROP 3 LASTPIN (-3950 650) SIG_NAME P12V_STBY\g
J 0
(-3940 660);
DISPLAY 0.659574 (-3940 660);
PAINT MONO (-3940 660);
DISPLAY INVISIBLE (-3940 660);
FORCEPROP 1 LAST PATH I223
J 0
(-3905 702);
DISPLAY 0.340426 (-3905 702);
PAINT GREEN (-3905 702);
DISPLAY INVISIBLE (-3905 702);
FORCEPROP 2 LAST CDS_LIB mstr_symbols
J 0
(-3950 700);
PAINT ORANGE (-3950 700);
DISPLAY INVISIBLE (-3950 700);
FORCEPROP 1 LAST SIZE 1B
J 0
(-3905 722);
DISPLAY 0.340426 (-3905 722);
PAINT GREEN (-3905 722);
DISPLAY INVISIBLE (-3905 722);
FORCEPROP 1 LAST VOLTAGE 12.0V
J 0
(-3995 657);
DISPLAY 0.340426 (-3995 657);
PAINT SKYBLUE (-3995 657);
DISPLAY INVISIBLE (-3995 657);
FORCEPROP 1 LAST BODY_TYPE PLUMBING
J 0
(-3995 657);
DISPLAY 0.340426 (-3995 657);
PAINT GREEN (-3995 657);
DISPLAY INVISIBLE (-3995 657);
FORCEPROP 1 LAST HDL_POWER P12V_STBY
J 0
(-4250 575);
DISPLAY 0.872340 (-4250 575);
PAINT ORANGE (-4250 575);
DISPLAY INVISIBLE (-4250 575);
FORCEADD OFFPAGE..2
(-2550 -50);
FORCEPROP 2 LAST $XR4 247 
J 0
(-1881 -50);
DISPLAY 0.638298 (-1881 -50);
PAINT MONO (-1881 -50);
FORCEPROP 2 LAST $XR3 191 
J 0
(-2001 -50);
DISPLAY 0.638298 (-2001 -50);
PAINT MONO (-2001 -50);
FORCEPROP 2 LAST $XR2 157 
J 0
(-2121 -50);
DISPLAY 0.638298 (-2121 -50);
PAINT MONO (-2121 -50);
FORCEPROP 2 LAST $XR1 118 
J 0
(-2241 -50);
DISPLAY 0.638298 (-2241 -50);
PAINT MONO (-2241 -50);
FORCEPROP 2 LAST $XR0 196 
J 0
(-2361 -50);
DISPLAY 0.638298 (-2361 -50);
PAINT MONO (-2361 -50);
FORCEPROP 2 LAST CDS_LIB mstr_standard
J 0
(-2550 -50);
PAINT ORANGE (-2550 -50);
DISPLAY INVISIBLE (-2550 -50);
FORCEPROP 2 LAST PATH I224
J 0
(-2375 25);
DISPLAY 1.021277 (-2375 25);
PAINT ORANGE (-2375 25);
DISPLAY INVISIBLE (-2375 25);
FORCEPROP 1 LAST OFFPAGE TRUE
J 0
(-2225 -175);
DISPLAY 0.872340 (-2225 -175);
PAINT GREEN (-2225 -175);
DISPLAY INVISIBLE (-2225 -175);
FORCEPROP 1 LAST COMMENT_BODY TRUE
J 0
(-2595 -145);
DISPLAY 0.872340 (-2595 -145);
PAINT GREEN (-2595 -145);
DISPLAY INVISIBLE (-2595 -145);
FORCEADD FET_N..8
(-1500 1675);
FORCEPROP 1 LAST PART_NUMBER C79254-001
J 0
(-1300 1475);
DISPLAY 0.617021 (-1300 1475);
PAINT BLUE (-1300 1475);
FORCEPROP 1 LAST LOCATION Q6W1
J 0
(-1300 1675);
DISPLAY 0.617021 (-1300 1675);
PAINT AQUA (-1300 1675);
FORCEPROP 1 LAST VALUE 2N7002
J 0
(-1300 1625);
DISPLAY 0.617021 (-1300 1625);
PAINT SKYBLUE (-1300 1625);
FORCEPROP 1 LAST MATERIAL FET
J 0
(-1300 1575);
DISPLAY 0.617021 (-1300 1575);
PAINT SKYBLUE (-1300 1575);
FORCEPROP 2 LAST CDS_LIB mstr_discrete
J 0
(-1500 1675);
PAINT MONO (-1500 1675);
DISPLAY INVISIBLE (-1500 1675);
FORCEPROP 1 LAST PATH I225
J 0
(-1300 1725);
DISPLAY 0.978723 (-1300 1725);
PAINT BLUE (-1300 1725);
DISPLAY INVISIBLE (-1300 1725);
FORCEPROP 0 LAST ROOM HOT_SWAP
J 0
(-1300 1775);
DISPLAY 1.021277 (-1300 1775);
PAINT ORANGE (-1300 1775);
DISPLAY INVISIBLE (-1300 1775);
FORCEPROP 1 LAST PACK_TYPE SOT23LF
J 0
(-1300 1525);
DISPLAY 0.978723 (-1300 1525);
PAINT SKYBLUE (-1300 1525);
DISPLAY INVISIBLE (-1300 1525);
FORCEPROP 1 LASTPIN (-1500 1475) $PN 2
J 2
(-1442 1475);
DISPLAY 0.872340 (-1442 1475);
PAINT WHITE (-1442 1475);
DISPLAY INVISIBLE (-1442 1475);
FORCEPROP 1 LASTPIN (-1500 1875) $PN 3
J 2
(-1447 1840);
DISPLAY 0.872340 (-1447 1840);
PAINT WHITE (-1447 1840);
DISPLAY INVISIBLE (-1447 1840);
FORCEPROP 1 LASTPIN (-1700 1575) $PN 1
J 2
(-1697 1590);
DISPLAY 0.872340 (-1697 1590);
PAINT WHITE (-1697 1590);
DISPLAY INVISIBLE (-1697 1590);
FORCEADD OFFPAGE..1
(-2350 1575);
FORCEPROP 2 LAST $XR1 146 
J 0
(-2722 1575);
DISPLAY 0.638298 (-2722 1575);
PAINT MONO (-2722 1575);
FORCEPROP 2 LAST $XR0 137 
J 0
(-2602 1575);
DISPLAY 0.638298 (-2602 1575);
PAINT MONO (-2602 1575);
FORCEPROP 2 LAST CDS_LIB mstr_standard
J 0
(-2350 1575);
PAINT ORANGE (-2350 1575);
DISPLAY INVISIBLE (-2350 1575);
FORCEPROP 2 LAST PATH I226
J 0
(-2600 1625);
DISPLAY 1.021277 (-2600 1625);
PAINT ORANGE (-2600 1625);
DISPLAY INVISIBLE (-2600 1625);
FORCEPROP 1 LAST OFFPAGE TRUE
J 0
(-2025 1450);
DISPLAY 0.872340 (-2025 1450);
PAINT GREEN (-2025 1450);
DISPLAY INVISIBLE (-2025 1450);
FORCEPROP 1 LAST COMMENT_BODY TRUE
J 0
(-2225 1475);
DISPLAY 0.872340 (-2225 1475);
PAINT GREEN (-2225 1475);
DISPLAY INVISIBLE (-2225 1475);
FORCEADD GND..1
(-1500 1300);
FORCEPROP 3 LASTPIN (-1500 1350) SIG_NAME GND\g
J 0
(-1490 1360);
DISPLAY 0.659574 (-1490 1360);
PAINT MONO (-1490 1360);
DISPLAY INVISIBLE (-1490 1360);
FORCEPROP 1 LAST SIZE 1B
J 0
(-1425 1250);
DISPLAY 0.872340 (-1425 1250);
PAINT AQUA (-1425 1250);
DISPLAY INVISIBLE (-1425 1250);
FORCEPROP 1 LAST VOLTAGE 0.0V
J 0
(-1545 1257);
DISPLAY 0.340426 (-1545 1257);
PAINT SKYBLUE (-1545 1257);
DISPLAY INVISIBLE (-1545 1257);
FORCEPROP 1 LAST PATH I227
J 0
(-1425 1300);
DISPLAY 0.872340 (-1425 1300);
PAINT AQUA (-1425 1300);
DISPLAY INVISIBLE (-1425 1300);
FORCEPROP 2 LAST CDS_LIB mstr_symbols
J 0
(-1500 1300);
PAINT MONO (-1500 1300);
DISPLAY INVISIBLE (-1500 1300);
FORCEPROP 1 LAST BODY_TYPE PLUMBING
J 0
(-1545 1257);
DISPLAY 0.340426 (-1545 1257);
PAINT GREEN (-1545 1257);
DISPLAY INVISIBLE (-1545 1257);
FORCEPROP 1 LAST HDL_POWER GND
J 0
(-1500 1450);
DISPLAY 0.872340 (-1500 1450);
PAINT GREEN (-1500 1450);
DISPLAY INVISIBLE (-1500 1450);
FORCEADD SC22P50V2JN-4GP..1
(-700 -100);
FORCEPROP 2 LAST TOLERANCE 5%
J 0
(-650 -100);
DISPLAY 0.638298 (-650 -100);
PAINT GREEN (-650 -100);
FORCEPROP 1 LAST LOCATION C9W1
J 0
(-650 55);
DISPLAY 0.617021 (-650 55);
PAINT GREEN (-650 55);
FORCEPROP 2 LASTPIN (-700 -175) $PN 2
R 1
J 2
(-710 -185);
DISPLAY 0.808511 (-710 -185);
PAINT ORANGE (-710 -185);
FORCEPROP 2 LAST RATED 50V
J 0
(-650 -150);
DISPLAY 0.638298 (-650 -150);
PAINT GREEN (-650 -150);
FORCEPROP 0 LAST POP NOPOP
J 0
(-500 -250);
DISPLAY 0.638298 (-500 -250);
PAINT RED (-500 -250);
FORCEPROP 2 LAST PACK_SIZE 0402
J 0
(-650 -250);
DISPLAY 0.638298 (-650 -250);
PAINT GREEN (-650 -250);
FORCEPROP 2 LAST TYPE NPO
J 0
(-650 -200);
DISPLAY 0.638298 (-650 -200);
PAINT GREEN (-650 -200);
FORCEPROP 2 LASTPIN (-700 -25) $PN 1
R 1
J 0
(-710 -15);
DISPLAY 0.808511 (-710 -15);
PAINT ORANGE (-710 -15);
FORCEPROP 1 LAST VALUE SC22P50V2JN-4GP
J 0
(-650 0);
DISPLAY 0.617021 (-650 0);
PAINT GREEN (-650 0);
FORCEPROP 2 LAST ATTRIBUTE 22PF
J 0
(-650 -50);
DISPLAY 0.638298 (-650 -50);
PAINT GREEN (-650 -50);
FORCEPROP 1 LAST CDS_LMAN_SYM_OUTLINE -50,25,50,-25
J 0
(-700 -100);
DISPLAY 0.468085 (-700 -100);
PAINT GREEN (-700 -100);
DISPLAY INVISIBLE (-700 -100);
FORCEPROP 1 LAST PATH I235
J 0
(-700 -100);
DISPLAY 0.617021 (-700 -100);
PAINT GREEN (-700 -100);
DISPLAY INVISIBLE (-700 -100);
FORCEPROP 2 LAST CDS_LIB w_hdl
J 0
(-700 -100);
PAINT MONO (-700 -100);
DISPLAY INVISIBLE (-700 -100);
FORCEPROP 1 LAST PART_NUMBER 78.22034.1FL
J 0
(-700 -100);
DISPLAY 0.617021 (-700 -100);
PAINT GREEN (-700 -100);
DISPLAY INVISIBLE (-700 -100);
FORCEPROP 1 LAST PACK_TYPE SMD-BCG
J 0
(-700 -100);
DISPLAY 0.617021 (-700 -100);
PAINT GREEN (-700 -100);
DISPLAY INVISIBLE (-700 -100);
FORCEPROP 2 LAST SEC 1
J 0
(-675 -25);
DISPLAY 0.680851 (-675 -25);
PAINT MONO (-675 -25);
DISPLAY INVISIBLE (-675 -25);
FORCEPROP 2 LAST SEC_TYPE SMD-BCG
J 0
(-675 -25);
DISPLAY 1.021277 (-675 -25);
PAINT ORANGE (-675 -25);
DISPLAY INVISIBLE (-675 -25);
FORCEADD SC22P50V2JN-4GP..1
(-1050 175);
FORCEPROP 2 LASTPIN (-1050 250) $PN 1
R 1
J 0
(-1060 260);
DISPLAY 0.808511 (-1060 260);
PAINT ORANGE (-1060 260);
FORCEPROP 2 LAST TYPE NPO
J 0
(-1000 0);
DISPLAY 0.638298 (-1000 0);
PAINT GREEN (-1000 0);
FORCEPROP 2 LAST ATTRIBUTE 22PF
J 0
(-1000 150);
DISPLAY 0.638298 (-1000 150);
PAINT GREEN (-1000 150);
FORCEPROP 2 LAST RATED 50V
J 0
(-1000 50);
DISPLAY 0.638298 (-1000 50);
PAINT GREEN (-1000 50);
FORCEPROP 2 LAST PACK_SIZE 0402
J 0
(-1000 -50);
DISPLAY 0.638298 (-1000 -50);
PAINT GREEN (-1000 -50);
FORCEPROP 0 LAST POP NOPOP
J 0
(-1000 -100);
DISPLAY 0.638298 (-1000 -100);
PAINT RED (-1000 -100);
FORCEPROP 1 LAST LOCATION C9W2
J 0
(-1000 255);
DISPLAY 0.617021 (-1000 255);
PAINT GREEN (-1000 255);
FORCEPROP 1 LAST VALUE SC22P50V2JN-4GP
J 0
(-1000 200);
DISPLAY 0.617021 (-1000 200);
PAINT GREEN (-1000 200);
FORCEPROP 2 LAST TOLERANCE 5%
J 0
(-1000 100);
DISPLAY 0.638298 (-1000 100);
PAINT GREEN (-1000 100);
FORCEPROP 2 LASTPIN (-1050 100) $PN 2
R 1
J 2
(-1060 90);
DISPLAY 0.808511 (-1060 90);
PAINT ORANGE (-1060 90);
FORCEPROP 1 LAST PART_NUMBER 78.22034.1FL
J 0
(-1050 175);
DISPLAY 0.617021 (-1050 175);
PAINT GREEN (-1050 175);
DISPLAY INVISIBLE (-1050 175);
FORCEPROP 2 LAST CDS_LIB w_hdl
J 0
(-1050 175);
PAINT MONO (-1050 175);
DISPLAY INVISIBLE (-1050 175);
FORCEPROP 1 LAST PATH I236
J 0
(-1050 175);
DISPLAY 0.617021 (-1050 175);
PAINT GREEN (-1050 175);
DISPLAY INVISIBLE (-1050 175);
FORCEPROP 1 LAST CDS_LMAN_SYM_OUTLINE -50,25,50,-25
J 0
(-1050 175);
DISPLAY 0.468085 (-1050 175);
PAINT GREEN (-1050 175);
DISPLAY INVISIBLE (-1050 175);
FORCEPROP 1 LAST PACK_TYPE SMD-BCG
J 0
(-1050 175);
DISPLAY 0.617021 (-1050 175);
PAINT GREEN (-1050 175);
DISPLAY INVISIBLE (-1050 175);
FORCEPROP 2 LAST SEC 1
J 0
(-1025 250);
DISPLAY 0.680851 (-1025 250);
PAINT MONO (-1025 250);
DISPLAY INVISIBLE (-1025 250);
FORCEPROP 2 LAST SEC_TYPE SMD-BCG
J 0
(-1025 250);
DISPLAY 1.021277 (-1025 250);
PAINT ORANGE (-1025 250);
DISPLAY INVISIBLE (-1025 250);
FORCEADD AGND0..1
(-700 -250);
FORCEPROP 3 LASTPIN (-700 -200) SIG_NAME AGND_HSC\g
J 0
(-690 -190);
DISPLAY 0.659574 (-690 -190);
PAINT MONO (-690 -190);
DISPLAY INVISIBLE (-690 -190);
FORCEPROP 1 LAST HDL_POWER AGND_HSC
J 1
(-700 -300);
DISPLAY 0.617021 (-700 -300);
PAINT GREEN (-700 -300);
FORCEPROP 2 LAST ROOM VR_P3V3
J 0
(-725 -275);
PAINT ORANGE (-725 -275);
DISPLAY INVISIBLE (-725 -275);
FORCEPROP 2 LAST BOM_COST MIO_VRD_MAIN
J 0
(-675 -275);
PAINT ORANGE (-675 -275);
DISPLAY INVISIBLE (-675 -275);
FORCEPROP 1 LAST VOLTAGE 0
J 0
(-700 -250);
PAINT SKYBLUE (-700 -250);
DISPLAY INVISIBLE (-700 -250);
FORCEPROP 1 LAST PATH I237
J 0
(-625 -250);
DISPLAY 0.872340 (-625 -250);
PAINT AQUA (-625 -250);
DISPLAY INVISIBLE (-625 -250);
FORCEPROP 2 LAST CDS_LIB mstr_symbols
J 0
(-700 -250);
PAINT MONO (-700 -250);
DISPLAY INVISIBLE (-700 -250);
FORCEPROP 1 LAST BODY_TYPE PLUMBING
J 0
(-745 -293);
DISPLAY 0.340426 (-745 -293);
PAINT GREEN (-745 -293);
DISPLAY INVISIBLE (-745 -293);
FORCEADD AGND0..1
(-1050 -100);
FORCEPROP 3 LASTPIN (-1050 -50) SIG_NAME AGND_HSC\g
J 0
(-1040 -40);
DISPLAY 0.659574 (-1040 -40);
PAINT MONO (-1040 -40);
DISPLAY INVISIBLE (-1040 -40);
FORCEPROP 1 LAST HDL_POWER AGND_HSC
J 1
(-1050 -150);
DISPLAY 0.617021 (-1050 -150);
PAINT GREEN (-1050 -150);
FORCEPROP 2 LAST CDS_LIB mstr_symbols
J 0
(-1050 -100);
PAINT MONO (-1050 -100);
DISPLAY INVISIBLE (-1050 -100);
FORCEPROP 1 LAST PATH I238
J 0
(-975 -100);
DISPLAY 0.872340 (-975 -100);
PAINT AQUA (-975 -100);
DISPLAY INVISIBLE (-975 -100);
FORCEPROP 2 LAST ROOM VR_P3V3
J 0
(-1075 -125);
PAINT ORANGE (-1075 -125);
DISPLAY INVISIBLE (-1075 -125);
FORCEPROP 2 LAST BOM_COST MIO_VRD_MAIN
J 0
(-1025 -125);
PAINT ORANGE (-1025 -125);
DISPLAY INVISIBLE (-1025 -125);
FORCEPROP 1 LAST VOLTAGE 0
J 0
(-1050 -100);
PAINT SKYBLUE (-1050 -100);
DISPLAY INVISIBLE (-1050 -100);
FORCEPROP 1 LAST BODY_TYPE PLUMBING
J 0
(-1095 -143);
DISPLAY 0.340426 (-1095 -143);
PAINT GREEN (-1095 -143);
DISPLAY INVISIBLE (-1095 -143);
FORCEADD OFFPAGE..4
R 2
(-2850 4000);
FORCEPROP 2 LAST CDS_LIB mstr_standard
J 0
(-2850 4000);
PAINT MONO (-2850 4000);
DISPLAY INVISIBLE (-2850 4000);
FORCEPROP 2 LAST PATH I241
J 0
(-2800 4075);
DISPLAY 1.021277 (-2800 4075);
PAINT ORANGE (-2800 4075);
DISPLAY INVISIBLE (-2800 4075);
FORCEPROP 1 LAST OFFPAGE TRUE
J 2
(-3175 3875);
PAINT GREEN (-3175 3875);
DISPLAY INVISIBLE (-3175 3875);
FORCEPROP 1 LAST COMMENT_BODY TRUE
J 2
(-2825 3900);
DISPLAY 1.872340 (-2825 3900);
PAINT GREEN (-2825 3900);
DISPLAY INVISIBLE (-2825 3900);
FORCEPROP 2 LAST $XR0 199 
J 0
(-3276 4000);
DISPLAY 0.638298 (-3276 4000);
PAINT MONO (-3276 4000);
DISPLAY INVISIBLE (-3276 4000);
FORCEADD RES..1
(-1750 3800);
FORCEPROP 1 LAST VALUE 0.0
J 2
(-1775 3725);
DISPLAY 0.638298 (-1775 3725);
PAINT SKYBLUE (-1775 3725);
FORCEPROP 1 LASTPIN (-1850 3800) $PN 1
J 0
(-1838 3812);
DISPLAY 0.787234 (-1838 3812);
PAINT ORANGE (-1838 3812);
FORCEPROP 1 LAST LOCATION R9P15
J 0
(-1800 3850);
DISPLAY 0.638298 (-1800 3850);
PAINT SKYBLUE (-1800 3850);
FORCEPROP 1 LASTPIN (-1650 3800) $PN 2
J 0
(-1688 3812);
DISPLAY 0.787234 (-1688 3812);
PAINT ORANGE (-1688 3812);
FORCEPROP 1 LAST WATTAGE 1/16W
J 2
(-1700 3675);
DISPLAY 0.638298 (-1700 3675);
PAINT SKYBLUE (-1700 3675);
FORCEPROP 1 LAST TOLERANCE 5%
J 0
(-1750 3725);
DISPLAY 0.638298 (-1750 3725);
PAINT SKYBLUE (-1750 3725);
FORCEPROP 1 LAST PACK_TYPE 0402
J 0
(-1800 3575);
DISPLAY 0.638298 (-1800 3575);
PAINT SKYBLUE (-1800 3575);
FORCEPROP 1 LAST MATERIAL CHIP
J 0
(-1800 3625);
DISPLAY 0.638298 (-1800 3625);
PAINT SKYBLUE (-1800 3625);
FORCEPROP 1 LAST PART_NUMBER G21497-005
J 0
(-1800 3900);
DISPLAY 0.638298 (-1800 3900);
PAINT BLUE (-1800 3900);
FORCEPROP 2 LAST SEC 1
J 0
(-1800 4000);
DISPLAY 0.680851 (-1800 4000);
PAINT MONO (-1800 4000);
DISPLAY INVISIBLE (-1800 4000);
FORCEPROP 2 LAST SEC_TYPE 0402
J 0
(-1800 4000);
DISPLAY 1.021277 (-1800 4000);
PAINT ORANGE (-1800 4000);
DISPLAY INVISIBLE (-1800 4000);
FORCEPROP 2 LAST CDS_LIB mstr_discrete
J 0
(-1750 3800);
PAINT MONO (-1750 3800);
DISPLAY INVISIBLE (-1750 3800);
FORCEPROP 1 LAST PATH I243
J 0
(-1800 3950);
DISPLAY 0.978723 (-1800 3950);
PAINT WHITE (-1800 3950);
DISPLAY INVISIBLE (-1800 3950);
FORCEADD RES..2
(-2600 3550);
FORCEPROP 1 LAST WATTAGE 1/16W
J 0
(-2560 3525);
DISPLAY 0.617021 (-2560 3525);
PAINT SKYBLUE (-2560 3525);
FORCEPROP 1 LASTPIN (-2600 3650) $PN 1
J 0
(-2595 3612);
DISPLAY 0.617021 (-2595 3612);
PAINT ORANGE (-2595 3612);
FORCEPROP 1 LASTPIN (-2600 3450) $PN 2
J 0
(-2595 3460);
DISPLAY 0.617021 (-2595 3460);
PAINT ORANGE (-2595 3460);
FORCEPROP 1 LAST MATERIAL CHIP
J 0
(-2560 3475);
DISPLAY 0.617021 (-2560 3475);
PAINT SKYBLUE (-2560 3475);
FORCEPROP 1 LAST LOCATION R1D10
J 0
(-2555 3675);
DISPLAY 0.617021 (-2555 3675);
PAINT AQUA (-2555 3675);
FORCEPROP 1 LAST VALUE 10.0K
J 0
(-2555 3625);
DISPLAY 0.617021 (-2555 3625);
PAINT SKYBLUE (-2555 3625);
FORCEPROP 1 LAST TOLERANCE 1%
J 0
(-2555 3575);
DISPLAY 0.617021 (-2555 3575);
PAINT SKYBLUE (-2555 3575);
FORCEPROP 1 LAST PACK_TYPE 0402
J 0
(-2560 3375);
DISPLAY 0.617021 (-2560 3375);
PAINT SKYBLUE (-2560 3375);
FORCEPROP 1 LAST PART_NUMBER G21796-016
J 0
(-2560 3425);
DISPLAY 0.617021 (-2560 3425);
PAINT BLUE (-2560 3425);
FORCEPROP 2 LAST ROOM HOT_SWAP
J 0
(-2550 3725);
PAINT MONO (-2550 3725);
DISPLAY INVISIBLE (-2550 3725);
FORCEPROP 2 LAST SEC 1
J 0
(-2550 3775);
DISPLAY 0.680851 (-2550 3775);
PAINT MONO (-2550 3775);
DISPLAY INVISIBLE (-2550 3775);
FORCEPROP 2 LAST SEC_TYPE 0402
J 0
(-2550 3775);
DISPLAY 1.021277 (-2550 3775);
PAINT ORANGE (-2550 3775);
DISPLAY INVISIBLE (-2550 3775);
FORCEPROP 2 LAST CDS_LIB mstr_discrete
J 0
(-2600 3550);
PAINT MONO (-2600 3550);
DISPLAY INVISIBLE (-2600 3550);
FORCEPROP 1 LAST PATH I244
J 0
(-2550 3725);
DISPLAY 0.978723 (-2550 3725);
PAINT WHITE (-2550 3725);
DISPLAY INVISIBLE (-2550 3725);
FORCEPROP 2 LAST CDS_LOCATION R1D10
J 0
(-2555 3675);
DISPLAY 0.617021 (-2555 3675);
PAINT AQUA (-2555 3675);
DISPLAY INVISIBLE (-2555 3675);
FORCEADD RES..2
(-4575 3450);
FORCEPROP 1 LAST WATTAGE 1/16W
J 0
(-4535 3425);
DISPLAY 0.617021 (-4535 3425);
PAINT SKYBLUE (-4535 3425);
FORCEPROP 1 LAST TOLERANCE 1%
J 0
(-4530 3475);
DISPLAY 0.617021 (-4530 3475);
PAINT SKYBLUE (-4530 3475);
FORCEPROP 1 LASTPIN (-4575 3550) $PN 1
J 0
(-4570 3512);
DISPLAY 0.617021 (-4570 3512);
PAINT ORANGE (-4570 3512);
FORCEPROP 1 LASTPIN (-4575 3350) $PN 2
J 0
(-4570 3360);
DISPLAY 0.617021 (-4570 3360);
PAINT ORANGE (-4570 3360);
FORCEPROP 1 LAST PACK_TYPE 0402
J 0
(-4535 3275);
DISPLAY 0.617021 (-4535 3275);
PAINT SKYBLUE (-4535 3275);
FORCEPROP 0 LAST BOM_SS 64.16535.6DL
J 0
(-4525 3225);
DISPLAY 0.638298 (-4525 3225);
PAINT BROWN (-4525 3225);
DISPLAY BOTH (-4525 3225);
FORCEPROP 1 LAST LOCATION R1D14
J 0
(-4530 3575);
DISPLAY 0.617021 (-4530 3575);
PAINT AQUA (-4530 3575);
FORCEPROP 1 LAST VALUE 105.0K
J 0
(-4530 3525);
DISPLAY 0.617021 (-4530 3525);
PAINT SKYBLUE (-4530 3525);
FORCEPROP 1 LAST MATERIAL CHIP
J 0
(-4535 3375);
DISPLAY 0.617021 (-4535 3375);
PAINT SKYBLUE (-4535 3375);
FORCEPROP 0 LAST BOM_DS 64.15435.6DL
J 0
(-4525 3175);
DISPLAY 0.638298 (-4525 3175);
PAINT BROWN (-4525 3175);
DISPLAY BOTH (-4525 3175);
FORCEPROP 1 LAST PART_NUMBER G21796-099
J 0
(-4535 3325);
DISPLAY 0.617021 (-4535 3325);
PAINT BLUE (-4535 3325);
FORCEPROP 1 LAST PATH I246
J 0
(-4525 3625);
DISPLAY 0.978723 (-4525 3625);
PAINT WHITE (-4525 3625);
DISPLAY INVISIBLE (-4525 3625);
FORCEPROP 2 LAST SEC_TYPE 0402
J 0
(-4525 3675);
DISPLAY 1.021277 (-4525 3675);
PAINT ORANGE (-4525 3675);
DISPLAY INVISIBLE (-4525 3675);
FORCEPROP 2 LAST SEC 1
J 0
(-4525 3675);
DISPLAY 0.680851 (-4525 3675);
PAINT MONO (-4525 3675);
DISPLAY INVISIBLE (-4525 3675);
FORCEPROP 2 LAST CDS_LOCATION R1D14
J 0
(-4530 3575);
DISPLAY 0.617021 (-4530 3575);
PAINT AQUA (-4530 3575);
DISPLAY INVISIBLE (-4530 3575);
FORCEPROP 2 LAST CDS_LIB mstr_discrete
J 0
(-4575 3450);
PAINT MONO (-4575 3450);
DISPLAY INVISIBLE (-4575 3450);
FORCEPROP 0 LAST CDS_SEC 1
J 0
(-4525 3625);
PAINT MONO (-4525 3625);
DISPLAY INVISIBLE (-4525 3625);
FORCEADD 270KR2F-GP..1
(-1650 275);
FORCEPROP 1 LAST LOCATION R9P13
J 0
(-1625 450);
DISPLAY 0.617021 (-1625 450);
PAINT GREEN (-1625 450);
FORCEPROP 1 LAST VALUE 270KR2F-GP
J 0
(-1625 400);
DISPLAY 0.617021 (-1625 400);
PAINT GREEN (-1625 400);
FORCEPROP 2 LASTPIN (-1650 150) $PN 2
R 1
J 2
(-1660 140);
DISPLAY 0.808511 (-1660 140);
PAINT ORANGE (-1660 140);
FORCEPROP 2 LASTPIN (-1650 400) $PN 1
R 1
J 0
(-1660 410);
DISPLAY 0.808511 (-1660 410);
PAINT ORANGE (-1660 410);
FORCEPROP 2 LAST RATED 1/16W
J 0
(-1625 250);
DISPLAY 0.638298 (-1625 250);
PAINT GREEN (-1625 250);
FORCEPROP 2 LAST PACK_SIZE 0402
J 0
(-1625 200);
DISPLAY 0.638298 (-1625 200);
PAINT GREEN (-1625 200);
FORCEPROP 2 LAST ATTRIBUTE 270KOHM
J 0
(-1625 350);
DISPLAY 0.638298 (-1625 350);
PAINT GREEN (-1625 350);
FORCEPROP 2 LAST TOLERANCE 1%
J 0
(-1625 300);
DISPLAY 0.638298 (-1625 300);
PAINT GREEN (-1625 300);
FORCEPROP 1 LAST PACK_TYPE RCL_GP
J 0
(-1650 275);
DISPLAY 0.617021 (-1650 275);
PAINT GREEN (-1650 275);
DISPLAY INVISIBLE (-1650 275);
FORCEPROP 2 LAST SEC 1
J 0
(-1625 425);
DISPLAY 0.680851 (-1625 425);
PAINT MONO (-1625 425);
DISPLAY INVISIBLE (-1625 425);
FORCEPROP 2 LAST SEC_TYPE RCL_GP
J 0
(-1625 425);
DISPLAY 1.021277 (-1625 425);
PAINT ORANGE (-1625 425);
DISPLAY INVISIBLE (-1625 425);
FORCEPROP 1 LAST PART_NUMBER 64.27035.6DL
J 0
(-1650 275);
DISPLAY 0.617021 (-1650 275);
PAINT GREEN (-1650 275);
DISPLAY INVISIBLE (-1650 275);
FORCEPROP 2 LAST CDS_LIB w_hdl
J 0
(-1650 275);
DISPLAY INVISIBLE (-1650 275);
FORCEPROP 1 LAST PATH I249
J 0
(-1650 275);
DISPLAY 0.617021 (-1650 275);
PAINT GREEN (-1650 275);
DISPLAY INVISIBLE (-1650 275);
FORCEPROP 1 LAST CDS_LMAN_SYM_OUTLINE -50,75,50,-75
J 0
(-1650 275);
DISPLAY 0.468085 (-1650 275);
PAINT GREEN (-1650 275);
DISPLAY INVISIBLE (-1650 275);
FORCEADD 232KR2F-2-GP..1
R 1
(-800 1950);
FORCEPROP 1 LAST VALUE 232KR2F-2-GP
J 0
(-925 1975);
DISPLAY 0.617021 (-925 1975);
PAINT GREEN (-925 1975);
FORCEPROP 2 LAST PACK_SIZE 0402
J 0
(-725 1850);
DISPLAY 0.638298 (-725 1850);
PAINT GREEN (-725 1850);
FORCEPROP 2 LAST TOLERANCE 1%
J 0
(-725 1900);
DISPLAY 0.638298 (-725 1900);
PAINT GREEN (-725 1900);
FORCEPROP 2 LAST RATED 1/16W
J 0
(-975 1850);
DISPLAY 0.638298 (-975 1850);
PAINT GREEN (-975 1850);
FORCEPROP 2 LASTPIN (-675 1950) $PN 2
J 0
(-665 1960);
DISPLAY 0.808511 (-665 1960);
PAINT ORANGE (-665 1960);
FORCEPROP 2 LASTPIN (-925 1950) $PN 1
J 2
(-935 1960);
DISPLAY 0.808511 (-935 1960);
PAINT ORANGE (-935 1960);
FORCEPROP 1 LAST LOCATION R6W3
J 0
(-925 2025);
DISPLAY 0.617021 (-925 2025);
PAINT GREEN (-925 2025);
FORCEPROP 2 LAST ATTRIBUTE 232KOHM
J 0
(-975 1900);
DISPLAY 0.638298 (-975 1900);
PAINT GREEN (-975 1900);
FORCEPROP 1 LAST PACK_TYPE SMD-RG1
R 1
J 0
(-800 1950);
DISPLAY 0.617021 (-800 1950);
PAINT GREEN (-800 1950);
DISPLAY INVISIBLE (-800 1950);
FORCEPROP 2 LAST SEC 1
J 0
(-925 2075);
DISPLAY 0.680851 (-925 2075);
PAINT MONO (-925 2075);
DISPLAY INVISIBLE (-925 2075);
FORCEPROP 2 LAST SEC_TYPE SMD-RG1
J 0
(-925 2075);
DISPLAY 1.021277 (-925 2075);
PAINT ORANGE (-925 2075);
DISPLAY INVISIBLE (-925 2075);
FORCEPROP 1 LAST PART_NUMBER 64.23235.L0L
R 1
J 0
(-800 1950);
DISPLAY 0.617021 (-800 1950);
PAINT GREEN (-800 1950);
DISPLAY INVISIBLE (-800 1950);
FORCEPROP 2 LAST CDS_LIB w_hdl
R 1
J 0
(-800 1950);
DISPLAY INVISIBLE (-800 1950);
FORCEPROP 1 LAST PATH I250
R 1
J 0
(-800 1950);
DISPLAY 0.617021 (-800 1950);
PAINT GREEN (-800 1950);
DISPLAY INVISIBLE (-800 1950);
FORCEPROP 1 LAST CDS_LMAN_SYM_OUTLINE -50,75,50,-75
R 1
J 0
(-800 1950);
DISPLAY 0.468085 (-800 1950);
PAINT GREEN (-800 1950);
DISPLAY INVISIBLE (-800 1950);
FORCEADD RES..2
(-1975 375);
FORCEPROP 1 LASTPIN (-1975 275) $PN 2
J 0
(-1970 285);
DISPLAY 0.617021 (-1970 285);
PAINT ORANGE (-1970 285);
FORCEPROP 1 LAST PART_NUMBER G21796-059
J 0
(-1935 250);
DISPLAY 0.617021 (-1935 250);
PAINT BLUE (-1935 250);
FORCEPROP 1 LAST MATERIAL CHIP
J 0
(-1935 300);
DISPLAY 0.617021 (-1935 300);
PAINT SKYBLUE (-1935 300);
FORCEPROP 1 LAST WATTAGE 1/16W
J 0
(-1935 350);
DISPLAY 0.617021 (-1935 350);
PAINT SKYBLUE (-1935 350);
FORCEPROP 1 LAST TOLERANCE 1%
J 0
(-1930 400);
DISPLAY 0.617021 (-1930 400);
PAINT SKYBLUE (-1930 400);
FORCEPROP 1 LAST VALUE 3.74K
J 0
(-1930 450);
DISPLAY 0.617021 (-1930 450);
PAINT SKYBLUE (-1930 450);
FORCEPROP 1 LAST PACK_TYPE 0402
J 0
(-1935 200);
DISPLAY 0.617021 (-1935 200);
PAINT SKYBLUE (-1935 200);
FORCEPROP 1 LASTPIN (-1975 475) $PN 1
J 0
(-1970 437);
DISPLAY 0.617021 (-1970 437);
PAINT ORANGE (-1970 437);
FORCEPROP 1 LAST LOCATION R9P9
J 0
(-1930 500);
DISPLAY 0.617021 (-1930 500);
PAINT AQUA (-1930 500);
FORCEPROP 1 LAST PATH I251
J 0
(-1925 550);
DISPLAY 0.978723 (-1925 550);
PAINT WHITE (-1925 550);
DISPLAY INVISIBLE (-1925 550);
FORCEPROP 2 LAST SEC 1
J 0
(-1925 600);
PAINT MONO (-1925 600);
DISPLAY INVISIBLE (-1925 600);
FORCEPROP 2 LAST SEC_TYPE 0402
J 0
(-1925 600);
DISPLAY 1.021277 (-1925 600);
PAINT ORANGE (-1925 600);
DISPLAY INVISIBLE (-1925 600);
FORCEPROP 2 LAST ROOM V_SUPER
J 0
(-1925 550);
DISPLAY 1.021277 (-1925 550);
PAINT ORANGE (-1925 550);
DISPLAY INVISIBLE (-1925 550);
FORCEPROP 2 LAST CDS_LIB mstr_discrete
J 0
(-1975 375);
PAINT ORANGE (-1975 375);
DISPLAY INVISIBLE (-1975 375);
FORCEPROP 0 LAST CDS_SEC 1
J 0
(-1925 550);
DISPLAY INVISIBLE (-1925 550);
FORCEPROP 0 LAST CDS_LOCATION R9P9
J 0
(-1925 550);
DISPLAY INVISIBLE (-1925 550);
FORCEADD RES..2
(-1975 800);
FORCEPROP 1 LAST MATERIAL CHIP
J 0
(-1935 725);
DISPLAY 0.617021 (-1935 725);
PAINT SKYBLUE (-1935 725);
FORCEPROP 1 LAST TOLERANCE 1%
J 0
(-1930 825);
DISPLAY 0.617021 (-1930 825);
PAINT SKYBLUE (-1930 825);
FORCEPROP 1 LAST LOCATION R9P7
J 0
(-1930 925);
DISPLAY 0.617021 (-1930 925);
PAINT AQUA (-1930 925);
FORCEPROP 1 LAST VALUE 100.0K
J 0
(-1930 875);
DISPLAY 0.617021 (-1930 875);
PAINT SKYBLUE (-1930 875);
FORCEPROP 1 LAST WATTAGE 1/16W
J 0
(-1935 775);
DISPLAY 0.617021 (-1935 775);
PAINT SKYBLUE (-1935 775);
FORCEPROP 1 LAST PACK_TYPE 0402
J 0
(-1685 675);
DISPLAY 0.617021 (-1685 675);
PAINT SKYBLUE (-1685 675);
FORCEPROP 1 LASTPIN (-1975 700) $PN 2
J 0
(-1970 710);
DISPLAY 0.617021 (-1970 710);
PAINT ORANGE (-1970 710);
FORCEPROP 1 LASTPIN (-1975 900) $PN 1
J 0
(-1970 862);
DISPLAY 0.617021 (-1970 862);
PAINT ORANGE (-1970 862);
FORCEPROP 1 LAST PART_NUMBER G21796-010
J 0
(-1935 675);
DISPLAY 0.617021 (-1935 675);
PAINT BLUE (-1935 675);
FORCEPROP 1 LAST PATH I252
J 0
(-1925 975);
DISPLAY 0.978723 (-1925 975);
PAINT WHITE (-1925 975);
DISPLAY INVISIBLE (-1925 975);
FORCEPROP 2 LAST SEC 1
J 0
(-1925 1025);
PAINT MONO (-1925 1025);
DISPLAY INVISIBLE (-1925 1025);
FORCEPROP 2 LAST SEC_TYPE 0402
J 0
(-1925 1025);
DISPLAY 1.021277 (-1925 1025);
PAINT ORANGE (-1925 1025);
DISPLAY INVISIBLE (-1925 1025);
FORCEPROP 2 LAST ROOM V_SUPER
J 0
(-1925 975);
DISPLAY 1.021277 (-1925 975);
PAINT ORANGE (-1925 975);
DISPLAY INVISIBLE (-1925 975);
FORCEPROP 2 LAST CDS_LIB mstr_discrete
J 0
(-1975 800);
PAINT ORANGE (-1975 800);
DISPLAY INVISIBLE (-1975 800);
FORCEPROP 0 LAST CDS_SEC 1
J 0
(-1925 975);
DISPLAY INVISIBLE (-1925 975);
FORCEPROP 0 LAST CDS_LOCATION R9P7
J 0
(-1925 975);
DISPLAY INVISIBLE (-1925 975);
FORCEADD RES..2
(-4150 2825);
FORCEPROP 1 LAST WATTAGE 1/16W
J 0
(-4110 2800);
DISPLAY 0.617021 (-4110 2800);
PAINT SKYBLUE (-4110 2800);
FORCEPROP 1 LAST TOLERANCE 1%
J 0
(-4105 2850);
DISPLAY 0.617021 (-4105 2850);
PAINT SKYBLUE (-4105 2850);
FORCEPROP 1 LAST LOCATION R1D20
J 0
(-4105 2950);
DISPLAY 0.617021 (-4105 2950);
PAINT AQUA (-4105 2950);
FORCEPROP 1 LAST VALUE 200.0K
J 0
(-4105 2900);
DISPLAY 0.617021 (-4105 2900);
PAINT SKYBLUE (-4105 2900);
FORCEPROP 1 LASTPIN (-4150 2925) $PN 1
J 0
(-4145 2887);
DISPLAY 0.617021 (-4145 2887);
PAINT ORANGE (-4145 2887);
FORCEPROP 1 LASTPIN (-4150 2725) $PN 2
J 0
(-4145 2735);
DISPLAY 0.617021 (-4145 2735);
PAINT ORANGE (-4145 2735);
FORCEPROP 1 LAST MATERIAL CHIP
J 0
(-4110 2750);
DISPLAY 0.617021 (-4110 2750);
PAINT SKYBLUE (-4110 2750);
FORCEPROP 1 LAST PACK_TYPE 0402
J 0
(-4110 2650);
DISPLAY 0.617021 (-4110 2650);
PAINT SKYBLUE (-4110 2650);
FORCEPROP 1 LAST PART_NUMBER G21796-080
J 0
(-4110 2700);
DISPLAY 0.617021 (-4110 2700);
PAINT BLUE (-4110 2700);
FORCEPROP 0 LAST BOM_DS 64.16935.6DL
J 0
(-3950 2875);
DISPLAY 0.638298 (-3950 2875);
PAINT BROWN (-3950 2875);
DISPLAY BOTH (-3950 2875);
FORCEPROP 1 LAST PATH I253
J 0
(-4100 3000);
DISPLAY 0.978723 (-4100 3000);
PAINT WHITE (-4100 3000);
DISPLAY INVISIBLE (-4100 3000);
FORCEPROP 2 LAST ROOM BMC_VOLT_MONITOR
J 0
(-4100 3000);
DISPLAY 1.021277 (-4100 3000);
PAINT ORANGE (-4100 3000);
DISPLAY INVISIBLE (-4100 3000);
FORCEPROP 2 LAST SEC 1
J 0
(-4100 3050);
DISPLAY 0.680851 (-4100 3050);
PAINT MONO (-4100 3050);
DISPLAY INVISIBLE (-4100 3050);
FORCEPROP 2 LAST BOM_COST SM_HM
J 0
(-4100 3050);
DISPLAY 1.021277 (-4100 3050);
PAINT ORANGE (-4100 3050);
DISPLAY INVISIBLE (-4100 3050);
FORCEPROP 2 LAST SEC_TYPE 0402
J 0
(-4100 3050);
DISPLAY 1.021277 (-4100 3050);
PAINT ORANGE (-4100 3050);
DISPLAY INVISIBLE (-4100 3050);
FORCEPROP 2 LAST CDS_LIB mstr_discrete
J 0
(-4150 2825);
PAINT ORANGE (-4150 2825);
DISPLAY INVISIBLE (-4150 2825);
FORCEPROP 2 LAST CDS_LOCATION R1D20
J 0
(-4105 2950);
DISPLAY 0.617021 (-4105 2950);
PAINT AQUA (-4105 2950);
DISPLAY INVISIBLE (-4105 2950);
FORCEADD CAP_A..1
(-1025 3425);
FORCEPROP 1 LAST VALUE 0.1UF
J 0
(-975 3475);
DISPLAY 0.617021 (-975 3475);
PAINT SKYBLUE (-975 3475);
FORCEPROP 1 LASTPIN (-1025 3525) $PN 1
J 0
(-1015 3505);
DISPLAY 0.617021 (-1015 3505);
PAINT ORANGE (-1015 3505);
FORCEPROP 1 LAST MATERIAL EMPTY
J 0
(-975 3325);
DISPLAY 0.617021 (-975 3325);
PAINT RED (-975 3325);
FORCEPROP 1 LAST VOLTAGE 16V
J 0
(-975 3425);
DISPLAY 0.617021 (-975 3425);
PAINT SKYBLUE (-975 3425);
FORCEPROP 1 LAST LOCATION C9P17
J 0
(-975 3525);
DISPLAY 0.617021 (-975 3525);
PAINT AQUA (-975 3525);
FORCEPROP 1 LAST TOLERANCE 10%
J 0
(-975 3375);
DISPLAY 0.617021 (-975 3375);
PAINT SKYBLUE (-975 3375);
FORCEPROP 1 LASTPIN (-1025 3325) $PN 2
J 0
(-1015 3305);
DISPLAY 0.617021 (-1015 3305);
PAINT ORANGE (-1015 3305);
FORCEPROP 1 LAST PART_NUMBER A36096-030
J 0
(-975 3275);
DISPLAY 0.617021 (-975 3275);
PAINT BLUE (-975 3275);
FORCEPROP 1 LAST PACK_TYPE 0402V
J 0
(-975 3225);
DISPLAY 0.617021 (-975 3225);
PAINT SKYBLUE (-975 3225);
FORCEPROP 2 LAST CDS_LIB dev_discrete
J 0
(-1025 3425);
PAINT ORANGE (-1025 3425);
DISPLAY INVISIBLE (-1025 3425);
FORCEPROP 2 LAST CDS_LOCATION C9P17
J 0
(-975 3525);
DISPLAY 0.617021 (-975 3525);
PAINT AQUA (-975 3525);
DISPLAY INVISIBLE (-975 3525);
FORCEPROP 1 LAST PATH I36
J 0
(-975 3575);
DISPLAY 0.978723 (-975 3575);
PAINT WHITE (-975 3575);
DISPLAY INVISIBLE (-975 3575);
FORCEPROP 0 LAST ROOM HOT_SWAP
J 2
(-975 3575);
DISPLAY 1.021277 (-975 3575);
PAINT ORANGE (-975 3575);
DISPLAY INVISIBLE (-975 3575);
FORCEPROP 2 LAST SEC_TYPE 0402V
J 0
(-975 3625);
DISPLAY 1.021277 (-975 3625);
PAINT ORANGE (-975 3625);
DISPLAY INVISIBLE (-975 3625);
FORCEPROP 2 LAST SEC 1
J 0
(-975 3625);
DISPLAY 0.680851 (-975 3625);
PAINT MONO (-975 3625);
DISPLAY INVISIBLE (-975 3625);
FORCEADD OFFPAGE..4
R 2
(-1125 3625);
FORCEPROP 2 LAST $XR0 199 
J 0
(-1377 3625);
DISPLAY 0.638298 (-1377 3625);
PAINT MONO (-1377 3625);
FORCEPROP 2 LAST PATH I37
J 0
(-1075 3700);
DISPLAY 1.021277 (-1075 3700);
PAINT ORANGE (-1075 3700);
DISPLAY INVISIBLE (-1075 3700);
FORCEPROP 2 LAST CDS_LIB mstr_standard
J 0
(-1125 3625);
PAINT ORANGE (-1125 3625);
DISPLAY INVISIBLE (-1125 3625);
FORCEPROP 1 LAST OFFPAGE TRUE
J 2
(-1450 3500);
PAINT GREEN (-1450 3500);
DISPLAY INVISIBLE (-1450 3500);
FORCEPROP 1 LAST COMMENT_BODY TRUE
J 2
(-1100 3525);
DISPLAY 1.872340 (-1100 3525);
PAINT GREEN (-1100 3525);
DISPLAY INVISIBLE (-1100 3525);
FORCEADD OFFPAGE..4
R 2
(-1150 3150);
FORCEPROP 2 LAST $XR0 199 
J 0
(-1402 3150);
DISPLAY 0.638298 (-1402 3150);
PAINT MONO (-1402 3150);
FORCEPROP 2 LAST CDS_LIB mstr_standard
J 0
(-1150 3150);
PAINT ORANGE (-1150 3150);
DISPLAY INVISIBLE (-1150 3150);
FORCEPROP 2 LAST PATH I38
J 0
(-1100 3225);
DISPLAY 1.021277 (-1100 3225);
PAINT ORANGE (-1100 3225);
DISPLAY INVISIBLE (-1100 3225);
FORCEPROP 1 LAST OFFPAGE TRUE
J 2
(-1475 3025);
PAINT GREEN (-1475 3025);
DISPLAY INVISIBLE (-1475 3025);
FORCEPROP 1 LAST COMMENT_BODY TRUE
J 2
(-1125 3050);
DISPLAY 1.872340 (-1125 3050);
PAINT GREEN (-1125 3050);
DISPLAY INVISIBLE (-1125 3050);
FORCEADD AGND0..1
(-1025 3225);
FORCEPROP 3 LASTPIN (-1025 3275) SIG_NAME AGND_HSC\g
J 0
(-1015 3285);
DISPLAY 0.659574 (-1015 3285);
PAINT MONO (-1015 3285);
DISPLAY INVISIBLE (-1015 3285);
FORCEPROP 1 LAST HDL_POWER AGND_HSC
J 1
(-1025 3175);
DISPLAY 0.617021 (-1025 3175);
PAINT GREEN (-1025 3175);
FORCEPROP 2 LAST ROOM VR_P3V3
J 0
(-1050 3200);
PAINT ORANGE (-1050 3200);
DISPLAY INVISIBLE (-1050 3200);
FORCEPROP 1 LAST VOLTAGE 0
J 0
(-1025 3225);
PAINT SKYBLUE (-1025 3225);
DISPLAY INVISIBLE (-1025 3225);
FORCEPROP 2 LAST CDS_LIB mstr_symbols
J 0
(-1025 3225);
PAINT ORANGE (-1025 3225);
DISPLAY INVISIBLE (-1025 3225);
FORCEPROP 1 LAST PATH I39
J 0
(-950 3225);
DISPLAY 0.872340 (-950 3225);
PAINT AQUA (-950 3225);
DISPLAY INVISIBLE (-950 3225);
FORCEPROP 2 LAST BOM_COST MIO_VRD_MAIN
J 0
(-1000 3200);
PAINT ORANGE (-1000 3200);
DISPLAY INVISIBLE (-1000 3200);
FORCEPROP 1 LAST BODY_TYPE PLUMBING
J 0
(-1070 3182);
DISPLAY 0.340426 (-1070 3182);
PAINT GREEN (-1070 3182);
DISPLAY INVISIBLE (-1070 3182);
FORCEADD CAP_A..1
(-675 3000);
FORCEPROP 1 LAST PART_NUMBER A36096-030
J 0
(-625 2850);
DISPLAY 0.617021 (-625 2850);
PAINT BLUE (-625 2850);
FORCEPROP 1 LAST TOLERANCE 10%
J 0
(-625 2950);
DISPLAY 0.617021 (-625 2950);
PAINT SKYBLUE (-625 2950);
FORCEPROP 1 LAST MATERIAL EMPTY
J 0
(-625 2900);
DISPLAY 0.617021 (-625 2900);
PAINT RED (-625 2900);
FORCEPROP 1 LAST VALUE 0.1UF
J 0
(-625 3050);
DISPLAY 0.617021 (-625 3050);
PAINT SKYBLUE (-625 3050);
FORCEPROP 1 LAST VOLTAGE 16V
J 0
(-625 3000);
DISPLAY 0.617021 (-625 3000);
PAINT SKYBLUE (-625 3000);
FORCEPROP 1 LAST LOCATION C9P16
J 0
(-625 3100);
DISPLAY 0.617021 (-625 3100);
PAINT AQUA (-625 3100);
FORCEPROP 1 LAST PACK_TYPE 0402V
J 0
(-625 2800);
DISPLAY 0.617021 (-625 2800);
PAINT SKYBLUE (-625 2800);
FORCEPROP 1 LASTPIN (-675 2900) $PN 2
J 0
(-665 2880);
DISPLAY 0.787234 (-665 2880);
PAINT ORANGE (-665 2880);
DISPLAY INVISIBLE (-665 2880);
FORCEPROP 2 LAST CDS_LIB dev_discrete
J 0
(-675 3000);
PAINT ORANGE (-675 3000);
DISPLAY INVISIBLE (-675 3000);
FORCEPROP 1 LASTPIN (-675 3100) $PN 1
J 0
(-665 3080);
DISPLAY 0.787234 (-665 3080);
PAINT ORANGE (-665 3080);
DISPLAY INVISIBLE (-665 3080);
FORCEPROP 1 LAST PATH I40
J 0
(-625 3150);
DISPLAY 0.978723 (-625 3150);
PAINT WHITE (-625 3150);
DISPLAY INVISIBLE (-625 3150);
FORCEPROP 0 LAST ROOM HOT_SWAP
J 2
(-625 3150);
DISPLAY 1.021277 (-625 3150);
PAINT ORANGE (-625 3150);
DISPLAY INVISIBLE (-625 3150);
FORCEPROP 2 LAST CDS_LOCATION C9P16
J 0
(-625 3100);
DISPLAY 0.617021 (-625 3100);
PAINT AQUA (-625 3100);
DISPLAY INVISIBLE (-625 3100);
FORCEPROP 2 LAST CDS_SEC 1
J 0
(-625 3200);
DISPLAY 1.021277 (-625 3200);
PAINT ORANGE (-625 3200);
DISPLAY INVISIBLE (-625 3200);
FORCEADD AGND0..1
(-675 2725);
FORCEPROP 3 LASTPIN (-675 2775) SIG_NAME AGND_HSC\g
J 0
(-665 2785);
DISPLAY 0.659574 (-665 2785);
PAINT MONO (-665 2785);
DISPLAY INVISIBLE (-665 2785);
FORCEPROP 1 LAST HDL_POWER AGND_HSC
J 1
(-675 2675);
DISPLAY 0.617021 (-675 2675);
PAINT GREEN (-675 2675);
FORCEPROP 2 LAST ROOM VR_P3V3
J 0
(-700 2700);
PAINT ORANGE (-700 2700);
DISPLAY INVISIBLE (-700 2700);
FORCEPROP 1 LAST PATH I41
J 0
(-600 2725);
DISPLAY 0.872340 (-600 2725);
PAINT AQUA (-600 2725);
DISPLAY INVISIBLE (-600 2725);
FORCEPROP 2 LAST BOM_COST MIO_VRD_MAIN
J 0
(-650 2700);
PAINT ORANGE (-650 2700);
DISPLAY INVISIBLE (-650 2700);
FORCEPROP 2 LAST CDS_LIB mstr_symbols
J 0
(-675 2725);
PAINT ORANGE (-675 2725);
DISPLAY INVISIBLE (-675 2725);
FORCEPROP 1 LAST VOLTAGE 0
J 0
(-675 2725);
PAINT SKYBLUE (-675 2725);
DISPLAY INVISIBLE (-675 2725);
FORCEPROP 1 LAST BODY_TYPE PLUMBING
J 0
(-720 2682);
DISPLAY 0.340426 (-720 2682);
PAINT GREEN (-720 2682);
DISPLAY INVISIBLE (-720 2682);
FORCEADD CAP_A..1
(-175 3425);
FORCEPROP 1 LAST PART_NUMBER A36096-030
J 0
(-125 3275);
DISPLAY 0.617021 (-125 3275);
PAINT BLUE (-125 3275);
FORCEPROP 1 LAST VOLTAGE 16V
J 0
(-125 3425);
DISPLAY 0.617021 (-125 3425);
PAINT SKYBLUE (-125 3425);
FORCEPROP 1 LAST TOLERANCE 10%
J 0
(-125 3375);
DISPLAY 0.617021 (-125 3375);
PAINT SKYBLUE (-125 3375);
FORCEPROP 1 LAST PACK_TYPE 0402V
J 0
(-125 3225);
DISPLAY 0.617021 (-125 3225);
PAINT SKYBLUE (-125 3225);
FORCEPROP 1 LAST MATERIAL EMPTY
J 0
(-125 3325);
DISPLAY 0.617021 (-125 3325);
PAINT RED (-125 3325);
FORCEPROP 1 LAST LOCATION C1D22
J 0
(-125 3525);
DISPLAY 0.617021 (-125 3525);
PAINT AQUA (-125 3525);
FORCEPROP 1 LAST VALUE 0.1UF
J 0
(-125 3475);
DISPLAY 0.617021 (-125 3475);
PAINT SKYBLUE (-125 3475);
FORCEPROP 1 LASTPIN (-175 3325) $PN 2
J 0
(-165 3305);
DISPLAY 0.787234 (-165 3305);
PAINT ORANGE (-165 3305);
DISPLAY INVISIBLE (-165 3305);
FORCEPROP 2 LAST CDS_LIB dev_discrete
J 0
(-175 3425);
PAINT ORANGE (-175 3425);
DISPLAY INVISIBLE (-175 3425);
FORCEPROP 1 LASTPIN (-175 3525) $PN 1
J 0
(-165 3505);
DISPLAY 0.787234 (-165 3505);
PAINT ORANGE (-165 3505);
DISPLAY INVISIBLE (-165 3505);
FORCEPROP 2 LAST CDS_LOCATION C1D22
J 0
(-125 3525);
DISPLAY 0.617021 (-125 3525);
PAINT AQUA (-125 3525);
DISPLAY INVISIBLE (-125 3525);
FORCEPROP 1 LAST PATH I42
J 0
(-125 3575);
DISPLAY 0.978723 (-125 3575);
PAINT WHITE (-125 3575);
DISPLAY INVISIBLE (-125 3575);
FORCEPROP 0 LAST ROOM HOT_SWAP
J 2
(-125 3575);
DISPLAY 1.021277 (-125 3575);
PAINT ORANGE (-125 3575);
DISPLAY INVISIBLE (-125 3575);
FORCEPROP 2 LAST CDS_SEC 1
J 0
(-125 3625);
DISPLAY 1.021277 (-125 3625);
PAINT ORANGE (-125 3625);
DISPLAY INVISIBLE (-125 3625);
FORCEADD RES..1
(250 3625);
FORCEPROP 1 LAST LOCATION R1D45
J 0
(200 3675);
DISPLAY 0.617021 (200 3675);
PAINT AQUA (200 3675);
FORCEPROP 1 LAST TOLERANCE 5%
J 0
(375 3550);
DISPLAY 0.617021 (375 3550);
PAINT SKYBLUE (375 3550);
FORCEPROP 1 LAST MATERIAL CHIP
J 0
(250 3525);
DISPLAY 0.617021 (250 3525);
PAINT SKYBLUE (250 3525);
FORCEPROP 1 LAST VALUE 0.0
J 2
(225 3525);
DISPLAY 0.617021 (225 3525);
PAINT SKYBLUE (225 3525);
FORCEPROP 1 LAST PACK_TYPE 0402
J 0
(450 3550);
DISPLAY 0.617021 (450 3550);
PAINT SKYBLUE (450 3550);
FORCEPROP 1 LAST PART_NUMBER G21497-005
J 0
(150 3475);
DISPLAY 0.617021 (150 3475);
PAINT BLUE (150 3475);
FORCEPROP 1 LAST WATTAGE 1/16W
J 2
(175 3550);
DISPLAY 0.617021 (175 3550);
PAINT SKYBLUE (175 3550);
FORCEPROP 1 LASTPIN (350 3625) $PN 2
J 0
(312 3637);
DISPLAY 0.787234 (312 3637);
PAINT ORANGE (312 3637);
DISPLAY INVISIBLE (312 3637);
FORCEPROP 2 LAST $SEC 1
J 0
(200 3825);
DISPLAY 0.680851 (200 3825);
PAINT MONO (200 3825);
DISPLAY INVISIBLE (200 3825);
FORCEPROP 2 LAST CDS_SEC 1
J 0
(200 3825);
DISPLAY 1.021277 (200 3825);
PAINT ORANGE (200 3825);
DISPLAY INVISIBLE (200 3825);
FORCEPROP 2 LAST CDS_LIB mstr_discrete
J 0
(250 3625);
PAINT ORANGE (250 3625);
DISPLAY INVISIBLE (250 3625);
FORCEPROP 2 LAST CDS_LOCATION R1D45
J 0
(200 3675);
DISPLAY 0.617021 (200 3675);
PAINT AQUA (200 3675);
DISPLAY INVISIBLE (200 3675);
FORCEPROP 0 LAST ROOM HOT_SWAP
J 0
(200 3775);
DISPLAY 1.021277 (200 3775);
PAINT ORANGE (200 3775);
DISPLAY INVISIBLE (200 3775);
FORCEPROP 1 LASTPIN (150 3625) $PN 1
J 0
(162 3637);
DISPLAY 0.787234 (162 3637);
PAINT ORANGE (162 3637);
DISPLAY INVISIBLE (162 3637);
FORCEPROP 1 LAST PATH I43
J 0
(200 3775);
DISPLAY 0.978723 (200 3775);
PAINT WHITE (200 3775);
DISPLAY INVISIBLE (200 3775);
FORCEADD RES..1
(225 3150);
FORCEPROP 1 LAST PACK_TYPE 0402
J 0
(425 3075);
DISPLAY 0.617021 (425 3075);
PAINT SKYBLUE (425 3075);
FORCEPROP 1 LAST WATTAGE 1/16W
J 2
(150 3075);
DISPLAY 0.617021 (150 3075);
PAINT SKYBLUE (150 3075);
FORCEPROP 1 LAST VALUE 0.0
J 2
(200 3050);
DISPLAY 0.617021 (200 3050);
PAINT SKYBLUE (200 3050);
FORCEPROP 1 LAST PART_NUMBER G21497-005
J 0
(125 3000);
DISPLAY 0.617021 (125 3000);
PAINT BLUE (125 3000);
FORCEPROP 1 LAST MATERIAL CHIP
J 0
(225 3050);
DISPLAY 0.617021 (225 3050);
PAINT SKYBLUE (225 3050);
FORCEPROP 1 LAST LOCATION R1D44
J 0
(175 3200);
DISPLAY 0.617021 (175 3200);
PAINT AQUA (175 3200);
FORCEPROP 1 LAST TOLERANCE 5%
J 0
(350 3075);
DISPLAY 0.617021 (350 3075);
PAINT SKYBLUE (350 3075);
FORCEPROP 2 LAST CDS_LIB mstr_discrete
J 0
(225 3150);
PAINT ORANGE (225 3150);
DISPLAY INVISIBLE (225 3150);
FORCEPROP 2 LAST CDS_LOCATION R1D44
J 0
(175 3200);
DISPLAY 0.617021 (175 3200);
PAINT AQUA (175 3200);
DISPLAY INVISIBLE (175 3200);
FORCEPROP 1 LASTPIN (125 3150) $PN 1
J 0
(137 3162);
DISPLAY 0.787234 (137 3162);
PAINT ORANGE (137 3162);
DISPLAY INVISIBLE (137 3162);
FORCEPROP 1 LAST PATH I44
J 0
(175 3300);
DISPLAY 0.978723 (175 3300);
PAINT WHITE (175 3300);
DISPLAY INVISIBLE (175 3300);
FORCEPROP 0 LAST ROOM HOT_SWAP
J 0
(175 3300);
DISPLAY 1.021277 (175 3300);
PAINT ORANGE (175 3300);
DISPLAY INVISIBLE (175 3300);
FORCEPROP 2 LAST $SEC 1
J 0
(175 3350);
DISPLAY 0.680851 (175 3350);
PAINT MONO (175 3350);
DISPLAY INVISIBLE (175 3350);
FORCEPROP 2 LAST CDS_SEC 1
J 0
(175 3350);
DISPLAY 1.021277 (175 3350);
PAINT ORANGE (175 3350);
DISPLAY INVISIBLE (175 3350);
FORCEPROP 1 LASTPIN (325 3150) $PN 2
J 0
(287 3162);
DISPLAY 0.787234 (287 3162);
PAINT ORANGE (287 3162);
DISPLAY INVISIBLE (287 3162);
FORCEADD OFFPAGE..4
R 2
(325 2350);
FORCEPROP 2 LAST $XR0 199 
J 0
(43 2350);
DISPLAY 0.638298 (43 2350);
PAINT MONO (43 2350);
FORCEPROP 2 LAST CDS_LIB mstr_standard
J 0
(325 2350);
PAINT ORANGE (325 2350);
DISPLAY INVISIBLE (325 2350);
FORCEPROP 2 LAST PATH I45
J 0
(375 2425);
DISPLAY 1.021277 (375 2425);
PAINT ORANGE (375 2425);
DISPLAY INVISIBLE (375 2425);
FORCEPROP 1 LAST OFFPAGE TRUE
J 2
(0 2225);
PAINT GREEN (0 2225);
DISPLAY INVISIBLE (0 2225);
FORCEPROP 1 LAST COMMENT_BODY TRUE
J 2
(350 2250);
DISPLAY 1.872340 (350 2250);
PAINT GREEN (350 2250);
DISPLAY INVISIBLE (350 2250);
FORCEADD OFFPAGE..4
R 2
(325 2250);
FORCEPROP 2 LAST $XR0 199 
J 0
(43 2250);
DISPLAY 0.638298 (43 2250);
PAINT MONO (43 2250);
FORCEPROP 2 LAST CDS_LIB mstr_standard
J 0
(325 2250);
PAINT ORANGE (325 2250);
DISPLAY INVISIBLE (325 2250);
FORCEPROP 2 LAST PATH I46
J 0
(375 2325);
DISPLAY 1.021277 (375 2325);
PAINT ORANGE (375 2325);
DISPLAY INVISIBLE (375 2325);
FORCEPROP 1 LAST OFFPAGE TRUE
J 2
(0 2125);
PAINT GREEN (0 2125);
DISPLAY INVISIBLE (0 2125);
FORCEPROP 1 LAST COMMENT_BODY TRUE
J 2
(350 2150);
DISPLAY 1.872340 (350 2150);
PAINT GREEN (350 2150);
DISPLAY INVISIBLE (350 2150);
FORCEADD RES..2
(875 2800);
FORCEPROP 1 LAST VALUE 10.0
J 0
(920 2875);
DISPLAY 0.617021 (920 2875);
PAINT SKYBLUE (920 2875);
FORCEPROP 1 LAST PART_NUMBER G21796-066
J 0
(890 2575);
DISPLAY 0.617021 (890 2575);
PAINT BLUE (890 2575);
FORCEPROP 1 LAST PACK_TYPE 0402
J 0
(915 2625);
DISPLAY 0.617021 (915 2625);
PAINT SKYBLUE (915 2625);
FORCEPROP 1 LAST MATERIAL CHIP
J 0
(915 2725);
DISPLAY 0.617021 (915 2725);
PAINT SKYBLUE (915 2725);
FORCEPROP 1 LAST TOLERANCE 1%
J 0
(920 2825);
DISPLAY 0.617021 (920 2825);
PAINT SKYBLUE (920 2825);
FORCEPROP 1 LAST WATTAGE 1/16W
J 0
(915 2775);
DISPLAY 0.617021 (915 2775);
PAINT SKYBLUE (915 2775);
FORCEPROP 1 LAST LOCATION R9P27
J 0
(920 2925);
DISPLAY 0.617021 (920 2925);
PAINT AQUA (920 2925);
FORCEPROP 1 LASTPIN (875 2700) $PN 2
J 0
(880 2710);
DISPLAY 0.787234 (880 2710);
PAINT ORANGE (880 2710);
DISPLAY INVISIBLE (880 2710);
FORCEPROP 2 LAST CDS_LIB mstr_discrete
J 0
(875 2800);
PAINT ORANGE (875 2800);
DISPLAY INVISIBLE (875 2800);
FORCEPROP 2 LAST CDS_SEC 1
J 0
(925 3025);
DISPLAY 1.021277 (925 3025);
PAINT ORANGE (925 3025);
DISPLAY INVISIBLE (925 3025);
FORCEPROP 2 LAST $SEC 1
J 0
(925 3025);
DISPLAY 0.680851 (925 3025);
PAINT MONO (925 3025);
DISPLAY INVISIBLE (925 3025);
FORCEPROP 1 LAST PATH I47
J 0
(925 2975);
DISPLAY 0.978723 (925 2975);
PAINT WHITE (925 2975);
DISPLAY INVISIBLE (925 2975);
FORCEPROP 2 LAST CDS_LOCATION R9P27
J 0
(920 2925);
DISPLAY 0.617021 (920 2925);
PAINT AQUA (920 2925);
DISPLAY INVISIBLE (920 2925);
FORCEPROP 1 LASTPIN (875 2900) $PN 1
J 0
(880 2862);
DISPLAY 0.787234 (880 2862);
PAINT ORANGE (880 2862);
DISPLAY INVISIBLE (880 2862);
FORCEPROP 0 LAST ROOM HOT_SWAP
J 0
(925 3025);
DISPLAY 1.021277 (925 3025);
PAINT ORANGE (925 3025);
DISPLAY INVISIBLE (925 3025);
FORCEADD RES..2
R 2
(750 2800);
FORCEPROP 1 LAST WATTAGE 1/16W
J 2
(710 2775);
DISPLAY 0.617021 (710 2775);
PAINT SKYBLUE (710 2775);
FORCEPROP 1 LAST PART_NUMBER G21796-066
J 2
(710 2675);
DISPLAY 0.617021 (710 2675);
PAINT BLUE (710 2675);
FORCEPROP 1 LAST LOCATION R1D46
J 2
(705 2925);
DISPLAY 0.617021 (705 2925);
PAINT AQUA (705 2925);
FORCEPROP 1 LAST TOLERANCE 1%
J 2
(705 2825);
DISPLAY 0.617021 (705 2825);
PAINT SKYBLUE (705 2825);
FORCEPROP 1 LAST VALUE 10.0
J 2
(705 2875);
DISPLAY 0.617021 (705 2875);
PAINT SKYBLUE (705 2875);
FORCEPROP 1 LAST PACK_TYPE 0402
J 2
(710 2625);
DISPLAY 0.617021 (710 2625);
PAINT SKYBLUE (710 2625);
FORCEPROP 1 LAST MATERIAL CHIP
J 2
(710 2725);
DISPLAY 0.617021 (710 2725);
PAINT SKYBLUE (710 2725);
FORCEPROP 1 LASTPIN (750 2700) $PN 2
J 2
(745 2710);
DISPLAY 0.787234 (745 2710);
PAINT ORANGE (745 2710);
DISPLAY INVISIBLE (745 2710);
FORCEPROP 2 LAST CDS_LIB mstr_discrete
J 2
(750 2800);
PAINT ORANGE (750 2800);
DISPLAY INVISIBLE (750 2800);
FORCEPROP 1 LASTPIN (750 2900) $PN 1
J 2
(745 2862);
DISPLAY 0.787234 (745 2862);
PAINT ORANGE (745 2862);
DISPLAY INVISIBLE (745 2862);
FORCEPROP 0 LAST ROOM HOT_SWAP
J 2
(700 3025);
DISPLAY 0.808511 (700 3025);
PAINT ORANGE (700 3025);
DISPLAY INVISIBLE (700 3025);
FORCEPROP 1 LAST PATH I48
J 2
(700 2975);
DISPLAY 0.978723 (700 2975);
PAINT WHITE (700 2975);
DISPLAY INVISIBLE (700 2975);
FORCEPROP 2 LAST CDS_LOCATION R1D46
J 2
(705 2925);
DISPLAY 0.617021 (705 2925);
PAINT AQUA (705 2925);
DISPLAY INVISIBLE (705 2925);
FORCEPROP 2 LAST CDS_SEC 1
J 0
(700 3025);
DISPLAY 1.021277 (700 3025);
PAINT ORANGE (700 3025);
DISPLAY INVISIBLE (700 3025);
FORCEPROP 2 LAST $SEC 1
J 0
(700 3025);
DISPLAY 0.680851 (700 3025);
PAINT MONO (700 3025);
DISPLAY INVISIBLE (700 3025);
FORCEADD RES_PWR..2
(1125 3200);
FORCEPROP 1 LAST VALUE 0.001
J 2
(1075 3050);
DISPLAY 0.617021 (1075 3050);
PAINT SKYBLUE (1075 3050);
FORCEPROP 2 LASTPIN (1025 3250) $PN 1
J 2
(1015 3260);
DISPLAY 0.617021 (1015 3260);
PAINT ORANGE (1015 3260);
FORCEPROP 1 LAST PACK_TYPE 6PAD
J 0
(1075 2975);
DISPLAY 0.617021 (1075 2975);
PAINT SKYBLUE (1075 2975);
FORCEPROP 2 LASTPIN (1025 3200) $PN 3
J 2
(1015 3210);
DISPLAY 0.617021 (1015 3210);
PAINT ORANGE (1015 3210);
FORCEPROP 2 LASTPIN (1025 3150) $PN 5
J 2
(1015 3160);
DISPLAY 0.617021 (1015 3160);
PAINT ORANGE (1015 3160);
FORCEPROP 2 LASTPIN (1225 3200) $PN 4
J 0
(1235 3210);
DISPLAY 0.617021 (1235 3210);
PAINT ORANGE (1235 3210);
FORCEPROP 1 LAST MATERIAL CHIP
J 0
(1175 3025);
DISPLAY 0.617021 (1175 3025);
PAINT SKYBLUE (1175 3025);
FORCEPROP 1 LAST TOLERANCE 1%
J 0
(1175 3050);
DISPLAY 0.617021 (1175 3050);
PAINT SKYBLUE (1175 3050);
FORCEPROP 2 LASTPIN (1225 3150) $PN 6
J 0
(1235 3160);
DISPLAY 0.617021 (1235 3160);
PAINT ORANGE (1235 3160);
FORCEPROP 2 LASTPIN (1225 3250) $PN 2
J 0
(1235 3260);
DISPLAY 0.617021 (1235 3260);
PAINT ORANGE (1235 3260);
FORCEPROP 1 LAST LOCATION R9R1
J 0
(1075 3325);
DISPLAY 0.617021 (1075 3325);
PAINT AQUA (1075 3325);
FORCEPROP 1 LAST PART_NUMBER E74391-005
J 0
(1075 3355);
DISPLAY 0.617021 (1075 3355);
PAINT BLUE (1075 3355);
FORCEPROP 0 LAST BOM_DS 064.0U505.0C71
J 0
(1325 3375);
DISPLAY 0.638298 (1325 3375);
PAINT BROWN (1325 3375);
DISPLAY BOTH (1325 3375);
FORCEPROP 1 LAST WATTAGE 3W
J 0
(1050 3025);
DISPLAY 0.617021 (1050 3025);
PAINT SKYBLUE (1050 3025);
FORCEPROP 1 LAST CDS_LMAN_SYM_OUTLINE -50,100,50,-100
J 0
(1125 3200);
DISPLAY 0.468085 (1125 3200);
PAINT GREEN (1125 3200);
DISPLAY INVISIBLE (1125 3200);
FORCEPROP 2 LAST CDS_LIB mstr_discrete
J 0
(1125 3200);
PAINT ORANGE (1125 3200);
DISPLAY INVISIBLE (1125 3200);
FORCEPROP 2 LAST CDS_LOCATION R9R1
J 0
(1075 3325);
DISPLAY 0.617021 (1075 3325);
PAINT AQUA (1075 3325);
DISPLAY INVISIBLE (1075 3325);
FORCEPROP 0 LAST ROOM HOT_SWAP
J 0
(1075 3450);
DISPLAY 1.021277 (1075 3450);
PAINT ORANGE (1075 3450);
DISPLAY INVISIBLE (1075 3450);
FORCEPROP 1 LAST PATH I49
J 0
(1075 3380);
DISPLAY 0.617021 (1075 3380);
PAINT GREEN (1075 3380);
DISPLAY INVISIBLE (1075 3380);
FORCEPROP 2 LAST SEC 1
J 0
(1075 3425);
DISPLAY 0.680851 (1075 3425);
PAINT MONO (1075 3425);
DISPLAY INVISIBLE (1075 3425);
FORCEPROP 2 LAST SEC_TYPE 6PAD
J 0
(1075 3425);
DISPLAY 1.021277 (1075 3425);
PAINT ORANGE (1075 3425);
DISPLAY INVISIBLE (1075 3425);
FORCEADD RES_PWR..2
(1125 3600);
FORCEPROP 1 LAST MATERIAL CHIP
J 0
(1175 3425);
DISPLAY 0.617021 (1175 3425);
PAINT SKYBLUE (1175 3425);
FORCEPROP 1 LAST TOLERANCE 1%
J 0
(1175 3450);
DISPLAY 0.617021 (1175 3450);
PAINT SKYBLUE (1175 3450);
FORCEPROP 1 LAST PACK_TYPE 6PAD
J 0
(1075 3400);
DISPLAY 0.617021 (1075 3400);
PAINT SKYBLUE (1075 3400);
FORCEPROP 2 LASTPIN (1225 3650) $PN 2
J 0
(1235 3660);
DISPLAY 0.617021 (1235 3660);
PAINT ORANGE (1235 3660);
FORCEPROP 2 LASTPIN (1025 3550) $PN 5
J 2
(1015 3560);
DISPLAY 0.617021 (1015 3560);
PAINT ORANGE (1015 3560);
FORCEPROP 2 LASTPIN (1225 3600) $PN 4
J 0
(1235 3610);
DISPLAY 0.617021 (1235 3610);
PAINT ORANGE (1235 3610);
FORCEPROP 2 LASTPIN (1225 3550) $PN 6
J 0
(1235 3560);
DISPLAY 0.617021 (1235 3560);
PAINT ORANGE (1235 3560);
FORCEPROP 1 LAST VALUE 0.001
J 2
(1075 3450);
DISPLAY 0.617021 (1075 3450);
PAINT SKYBLUE (1075 3450);
FORCEPROP 2 LASTPIN (1025 3650) $PN 1
J 2
(1015 3660);
DISPLAY 0.617021 (1015 3660);
PAINT ORANGE (1015 3660);
FORCEPROP 2 LASTPIN (1025 3600) $PN 3
J 2
(1015 3610);
DISPLAY 0.617021 (1015 3610);
PAINT ORANGE (1015 3610);
FORCEPROP 1 LAST PART_NUMBER E74391-005
J 0
(1075 3755);
DISPLAY 0.617021 (1075 3755);
PAINT BLUE (1075 3755);
FORCEPROP 1 LAST LOCATION R1D49
J 0
(1075 3725);
DISPLAY 0.617021 (1075 3725);
PAINT AQUA (1075 3725);
FORCEPROP 1 LAST WATTAGE 3W
J 0
(975 3375);
DISPLAY 0.617021 (975 3375);
PAINT SKYBLUE (975 3375);
FORCEPROP 0 LAST BOM_DS 064.0U505.0C71
J 0
(1075 3800);
DISPLAY 0.638298 (1075 3800);
PAINT BROWN (1075 3800);
DISPLAY BOTH (1075 3800);
FORCEPROP 2 LAST CDS_LIB mstr_discrete
J 0
(1125 3600);
PAINT ORANGE (1125 3600);
DISPLAY INVISIBLE (1125 3600);
FORCEPROP 1 LAST CDS_LMAN_SYM_OUTLINE -50,100,50,-100
J 0
(1125 3600);
DISPLAY 0.468085 (1125 3600);
PAINT GREEN (1125 3600);
DISPLAY INVISIBLE (1125 3600);
FORCEPROP 1 LAST PATH I50
J 0
(1075 3780);
DISPLAY 0.617021 (1075 3780);
PAINT GREEN (1075 3780);
DISPLAY INVISIBLE (1075 3780);
FORCEPROP 2 LAST CDS_LOCATION R1D49
J 0
(1075 3725);
DISPLAY 0.617021 (1075 3725);
PAINT AQUA (1075 3725);
DISPLAY INVISIBLE (1075 3725);
FORCEPROP 2 LAST SEC_TYPE 6PAD
J 0
(1075 3825);
DISPLAY 1.021277 (1075 3825);
PAINT ORANGE (1075 3825);
DISPLAY INVISIBLE (1075 3825);
FORCEPROP 2 LAST SEC 1
J 0
(1075 3825);
DISPLAY 0.680851 (1075 3825);
PAINT MONO (1075 3825);
DISPLAY INVISIBLE (1075 3825);
FORCEPROP 0 LAST ROOM HOT_SWAP
J 0
(1075 3850);
DISPLAY 1.021277 (1075 3850);
PAINT ORANGE (1075 3850);
DISPLAY INVISIBLE (1075 3850);
FORCEADD RES..2
R 2
(1350 2800);
FORCEPROP 1 LAST VALUE 10.0
J 2
(1305 2875);
DISPLAY 0.617021 (1305 2875);
PAINT SKYBLUE (1305 2875);
FORCEPROP 1 LAST TOLERANCE 1%
J 2
(1305 2825);
DISPLAY 0.617021 (1305 2825);
PAINT SKYBLUE (1305 2825);
FORCEPROP 1 LAST LOCATION R9P26
J 2
(1305 2925);
DISPLAY 0.617021 (1305 2925);
PAINT AQUA (1305 2925);
FORCEPROP 1 LAST MATERIAL CHIP
J 2
(1310 2725);
DISPLAY 0.617021 (1310 2725);
PAINT SKYBLUE (1310 2725);
FORCEPROP 1 LAST PACK_TYPE 0402
J 2
(1310 2625);
DISPLAY 0.617021 (1310 2625);
PAINT SKYBLUE (1310 2625);
FORCEPROP 1 LAST PART_NUMBER G21796-066
J 2
(1310 2675);
DISPLAY 0.617021 (1310 2675);
PAINT BLUE (1310 2675);
FORCEPROP 1 LAST WATTAGE 1/16W
J 2
(1310 2775);
DISPLAY 0.617021 (1310 2775);
PAINT SKYBLUE (1310 2775);
FORCEPROP 1 LASTPIN (1350 2700) $PN 2
J 2
(1345 2710);
DISPLAY 0.787234 (1345 2710);
PAINT ORANGE (1345 2710);
DISPLAY INVISIBLE (1345 2710);
FORCEPROP 2 LAST CDS_LIB mstr_discrete
J 2
(1350 2800);
PAINT ORANGE (1350 2800);
DISPLAY INVISIBLE (1350 2800);
FORCEPROP 1 LASTPIN (1350 2900) $PN 1
J 2
(1345 2862);
DISPLAY 0.787234 (1345 2862);
PAINT ORANGE (1345 2862);
DISPLAY INVISIBLE (1345 2862);
FORCEPROP 0 LAST ROOM HOT_SWAP
J 2
(1300 3025);
DISPLAY 1.021277 (1300 3025);
PAINT ORANGE (1300 3025);
DISPLAY INVISIBLE (1300 3025);
FORCEPROP 1 LAST PATH I51
J 2
(1300 2975);
DISPLAY 0.978723 (1300 2975);
PAINT WHITE (1300 2975);
DISPLAY INVISIBLE (1300 2975);
FORCEPROP 2 LAST CDS_LOCATION R9P26
J 2
(1305 2925);
DISPLAY 0.617021 (1305 2925);
PAINT AQUA (1305 2925);
DISPLAY INVISIBLE (1305 2925);
FORCEPROP 2 LAST $SEC 1
J 0
(1300 3025);
DISPLAY 0.680851 (1300 3025);
PAINT MONO (1300 3025);
DISPLAY INVISIBLE (1300 3025);
FORCEPROP 2 LAST CDS_SEC 1
J 0
(1300 3025);
DISPLAY 1.021277 (1300 3025);
PAINT ORANGE (1300 3025);
DISPLAY INVISIBLE (1300 3025);
FORCEADD RES..2
(1475 2800);
FORCEPROP 1 LAST WATTAGE 1/16W
J 0
(1515 2775);
DISPLAY 0.617021 (1515 2775);
PAINT SKYBLUE (1515 2775);
FORCEPROP 1 LAST MATERIAL CHIP
J 0
(1515 2725);
DISPLAY 0.617021 (1515 2725);
PAINT SKYBLUE (1515 2725);
FORCEPROP 1 LAST PACK_TYPE 0402
J 0
(1515 2625);
DISPLAY 0.617021 (1515 2625);
PAINT SKYBLUE (1515 2625);
FORCEPROP 1 LAST LOCATION R1D47
J 0
(1520 2925);
DISPLAY 0.617021 (1520 2925);
PAINT AQUA (1520 2925);
FORCEPROP 1 LAST TOLERANCE 1%
J 0
(1520 2825);
DISPLAY 0.617021 (1520 2825);
PAINT SKYBLUE (1520 2825);
FORCEPROP 1 LAST VALUE 10.0
J 0
(1520 2875);
DISPLAY 0.617021 (1520 2875);
PAINT SKYBLUE (1520 2875);
FORCEPROP 1 LAST PART_NUMBER G21796-066
J 0
(1465 2675);
DISPLAY 0.617021 (1465 2675);
PAINT BLUE (1465 2675);
FORCEPROP 1 LASTPIN (1475 2700) $PN 2
J 0
(1480 2710);
DISPLAY 0.787234 (1480 2710);
PAINT ORANGE (1480 2710);
DISPLAY INVISIBLE (1480 2710);
FORCEPROP 2 LAST CDS_LIB mstr_discrete
J 0
(1475 2800);
PAINT ORANGE (1475 2800);
DISPLAY INVISIBLE (1475 2800);
FORCEPROP 2 LAST CDS_SEC 1
J 0
(1525 3025);
DISPLAY 1.021277 (1525 3025);
PAINT ORANGE (1525 3025);
DISPLAY INVISIBLE (1525 3025);
FORCEPROP 2 LAST $SEC 1
J 0
(1525 3025);
DISPLAY 0.680851 (1525 3025);
PAINT MONO (1525 3025);
DISPLAY INVISIBLE (1525 3025);
FORCEPROP 2 LAST CDS_LOCATION R1D47
J 0
(1520 2925);
DISPLAY 0.617021 (1520 2925);
PAINT AQUA (1520 2925);
DISPLAY INVISIBLE (1520 2925);
FORCEPROP 1 LAST PATH I52
J 0
(1525 2975);
DISPLAY 0.978723 (1525 2975);
PAINT WHITE (1525 2975);
DISPLAY INVISIBLE (1525 2975);
FORCEPROP 0 LAST ROOM HOT_SWAP
J 0
(1525 3025);
DISPLAY 1.021277 (1525 3025);
PAINT ORANGE (1525 3025);
DISPLAY INVISIBLE (1525 3025);
FORCEPROP 1 LASTPIN (1475 2900) $PN 1
J 0
(1480 2862);
DISPLAY 0.787234 (1480 2862);
PAINT ORANGE (1480 2862);
DISPLAY INVISIBLE (1480 2862);
FORCEADD P12V_PSU..1
(900 3825);
FORCEPROP 3 LASTPIN (900 3775) SIG_NAME P12V_PSU\g
J 0
(910 3785);
DISPLAY 0.659574 (910 3785);
PAINT MONO (910 3785);
DISPLAY INVISIBLE (910 3785);
FORCEPROP 1 LAST VOLTAGE 12.0
J 0
(855 3782);
DISPLAY 0.340426 (855 3782);
PAINT SKYBLUE (855 3782);
DISPLAY INVISIBLE (855 3782);
FORCEPROP 2 LAST CDS_LIB mstr_symbols
J 0
(900 3825);
PAINT ORANGE (900 3825);
DISPLAY INVISIBLE (900 3825);
FORCEPROP 2 LAST BOM_COST NT_BASE_VRD
J 0
(900 3925);
DISPLAY 0.617021 (900 3925);
PAINT ORANGE (900 3925);
DISPLAY INVISIBLE (900 3925);
FORCEPROP 1 LAST PATH I53
J 0
(950 3850);
DISPLAY 0.872340 (950 3850);
PAINT AQUA (950 3850);
DISPLAY INVISIBLE (950 3850);
FORCEPROP 2 LAST ROOM P2V5_LAN_AUX_VR
J 0
(900 3925);
DISPLAY 0.617021 (900 3925);
PAINT ORANGE (900 3925);
DISPLAY INVISIBLE (900 3925);
FORCEPROP 1 LAST BODY_TYPE PLUMBING
J 0
(855 3782);
DISPLAY 0.340426 (855 3782);
PAINT GREEN (855 3782);
DISPLAY INVISIBLE (855 3782);
FORCEPROP 1 LAST HDL_POWER P12V_PSU
J 1
(900 3875);
DISPLAY 0.872340 (900 3875);
PAINT GREEN (900 3875);
DISPLAY INVISIBLE (900 3875);
FORCEADD MOSFETN_1D3S..1
R 1
(2275 3375);
FORCEPROP 1 LAST PART_NUMBER G68777-001
J 0
(2325 3525);
DISPLAY 0.617021 (2325 3525);
PAINT BLUE (2325 3525);
FORCEPROP 1 LAST LOCATION EU1E3
R 1
J 0
(2225 3525);
DISPLAY 0.617021 (2225 3525);
PAINT AQUA (2225 3525);
FORCEPROP 2 LASTPIN (2425 3375) $PN 2
J 0
(2435 3385);
DISPLAY 0.617021 (2435 3385);
PAINT ORANGE (2435 3385);
FORCEPROP 2 LASTPIN (2425 3325) $PN 1
J 0
(2435 3335);
DISPLAY 0.617021 (2435 3335);
PAINT ORANGE (2435 3335);
FORCEPROP 2 LASTPIN (2425 3425) $PN 3
J 0
(2435 3435);
DISPLAY 0.617021 (2435 3435);
PAINT ORANGE (2435 3435);
FORCEPROP 2 LASTPIN (2325 3175) $PN 4
R 1
J 2
(2315 3165);
DISPLAY 0.617021 (2315 3165);
PAINT ORANGE (2315 3165);
FORCEPROP 2 LASTPIN (2125 3325) $PN 5
J 2
(2115 3335);
DISPLAY 0.617021 (2115 3335);
PAINT ORANGE (2115 3335);
FORCEPROP 1 LAST MATERIAL IC
R 1
J 0
(2275 3525);
DISPLAY 0.617021 (2275 3525);
PAINT SKYBLUE (2275 3525);
FORCEPROP 0 LAST ROOM HOT_SWAP
R 1
J 0
(2125 3525);
DISPLAY 1.021277 (2125 3525);
PAINT ORANGE (2125 3525);
DISPLAY INVISIBLE (2125 3525);
FORCEPROP 1 LAST PATH I54
R 1
J 0
(2175 3525);
DISPLAY 0.978723 (2175 3525);
PAINT WHITE (2175 3525);
DISPLAY INVISIBLE (2175 3525);
FORCEPROP 2 LAST CDS_LOCATION EU1E3
R 1
J 0
(2225 3525);
DISPLAY 0.617021 (2225 3525);
PAINT AQUA (2225 3525);
DISPLAY INVISIBLE (2225 3525);
FORCEPROP 2 LAST CDS_LIB mstr_discrete
R 1
J 0
(2275 3375);
PAINT ORANGE (2275 3375);
DISPLAY INVISIBLE (2275 3375);
FORCEPROP 1 LAST PACK_TYPE SOT5
R 1
J 0
(2375 3525);
DISPLAY 0.957447 (2375 3525);
PAINT SKYBLUE (2375 3525);
DISPLAY INVISIBLE (2375 3525);
FORCEPROP 2 LAST SEC_TYPE SOT5
J 0
(2425 3525);
DISPLAY 1.021277 (2425 3525);
PAINT ORANGE (2425 3525);
DISPLAY INVISIBLE (2425 3525);
FORCEPROP 2 LAST SEC 1
J 0
(2425 3525);
DISPLAY 0.680851 (2425 3525);
PAINT MONO (2425 3525);
DISPLAY INVISIBLE (2425 3525);
FORCEADD OFFPAGE..4
R 2
(1400 2100);
FORCEPROP 2 LAST $XR0 199 
J 0
(1148 2100);
DISPLAY 0.638298 (1148 2100);
PAINT MONO (1148 2100);
FORCEPROP 2 LAST CDS_LIB mstr_standard
J 0
(1400 2100);
PAINT ORANGE (1400 2100);
DISPLAY INVISIBLE (1400 2100);
FORCEPROP 2 LAST PATH I55
J 0
(1450 2175);
DISPLAY 1.021277 (1450 2175);
PAINT ORANGE (1450 2175);
DISPLAY INVISIBLE (1450 2175);
FORCEPROP 1 LAST OFFPAGE TRUE
J 2
(1075 1975);
PAINT GREEN (1075 1975);
DISPLAY INVISIBLE (1075 1975);
FORCEPROP 1 LAST COMMENT_BODY TRUE
J 2
(1425 2000);
DISPLAY 1.872340 (1425 2000);
PAINT GREEN (1425 2000);
DISPLAY INVISIBLE (1425 2000);
FORCEADD RES..1
(2000 3075);
FORCEPROP 1 LAST WATTAGE 1/16W
J 2
(1900 2975);
DISPLAY 0.617021 (1900 2975);
PAINT SKYBLUE (1900 2975);
FORCEPROP 1 LAST LOCATION R1E1
J 0
(1950 3125);
DISPLAY 0.617021 (1950 3125);
PAINT AQUA (1950 3125);
FORCEPROP 1 LASTPIN (1900 3075) $PN 1
J 0
(1912 3087);
DISPLAY 0.617021 (1912 3087);
PAINT ORANGE (1912 3087);
FORCEPROP 1 LAST PACK_TYPE 0402
J 0
(1775 3025);
DISPLAY 0.617021 (1775 3025);
PAINT SKYBLUE (1775 3025);
FORCEPROP 1 LAST MATERIAL CHIP
J 0
(1800 2925);
DISPLAY 0.617021 (1800 2925);
PAINT SKYBLUE (1800 2925);
FORCEPROP 1 LASTPIN (2100 3075) $PN 2
J 0
(2062 3087);
DISPLAY 0.617021 (2062 3087);
PAINT ORANGE (2062 3087);
FORCEPROP 1 LAST PART_NUMBER G21796-066
J 0
(1950 3175);
DISPLAY 0.617021 (1950 3175);
PAINT BLUE (1950 3175);
FORCEPROP 1 LAST TOLERANCE 1%
J 0
(2075 3025);
DISPLAY 0.617021 (2075 3025);
PAINT SKYBLUE (2075 3025);
FORCEPROP 1 LAST VALUE 10.0
J 2
(2025 3025);
DISPLAY 0.617021 (2025 3025);
PAINT SKYBLUE (2025 3025);
FORCEPROP 0 LAST ROOM HOT_SWAP
J 0
(1950 3275);
DISPLAY 1.021277 (1950 3275);
PAINT ORANGE (1950 3275);
DISPLAY INVISIBLE (1950 3275);
FORCEPROP 1 LAST PATH I56
J 0
(1950 3225);
DISPLAY 0.978723 (1950 3225);
PAINT WHITE (1950 3225);
DISPLAY INVISIBLE (1950 3225);
FORCEPROP 2 LAST CDS_LOCATION R1E1
J 0
(1950 3125);
DISPLAY 0.617021 (1950 3125);
PAINT AQUA (1950 3125);
DISPLAY INVISIBLE (1950 3125);
FORCEPROP 2 LAST SEC 1
J 0
(1950 3275);
DISPLAY 0.680851 (1950 3275);
PAINT MONO (1950 3275);
DISPLAY INVISIBLE (1950 3275);
FORCEPROP 2 LAST SEC_TYPE 0402
J 0
(1950 3275);
DISPLAY 1.021277 (1950 3275);
PAINT ORANGE (1950 3275);
DISPLAY INVISIBLE (1950 3275);
FORCEPROP 2 LAST CDS_LIB mstr_discrete
J 0
(2000 3075);
PAINT ORANGE (2000 3075);
DISPLAY INVISIBLE (2000 3075);
FORCEADD MOSFETN_1D3S..1
R 1
(2300 2825);
FORCEPROP 2 LASTPIN (2450 2875) $PN 3
J 0
(2460 2885);
DISPLAY 0.617021 (2460 2885);
PAINT ORANGE (2460 2885);
FORCEPROP 1 LAST PART_NUMBER G68777-001
J 0
(2350 2975);
DISPLAY 0.617021 (2350 2975);
PAINT BLUE (2350 2975);
FORCEPROP 1 LAST MATERIAL IC
R 1
J 0
(2300 2975);
DISPLAY 0.617021 (2300 2975);
PAINT SKYBLUE (2300 2975);
FORCEPROP 2 LASTPIN (2150 2775) $PN 5
J 2
(2140 2785);
DISPLAY 0.617021 (2140 2785);
PAINT ORANGE (2140 2785);
FORCEPROP 2 LASTPIN (2450 2775) $PN 1
J 0
(2460 2785);
DISPLAY 0.617021 (2460 2785);
PAINT ORANGE (2460 2785);
FORCEPROP 2 LASTPIN (2450 2825) $PN 2
J 0
(2460 2835);
DISPLAY 0.617021 (2460 2835);
PAINT ORANGE (2460 2835);
FORCEPROP 2 LASTPIN (2350 2625) $PN 4
R 1
J 2
(2340 2615);
DISPLAY 0.617021 (2340 2615);
PAINT ORANGE (2340 2615);
FORCEPROP 1 LAST LOCATION EU9R1
R 1
J 0
(2175 2850);
DISPLAY 0.617021 (2175 2850);
PAINT AQUA (2175 2850);
FORCEPROP 2 LAST CDS_LIB mstr_discrete
J 0
(2300 2825);
PAINT ORANGE (2300 2825);
DISPLAY INVISIBLE (2300 2825);
FORCEPROP 2 LAST CDS_LOCATION EU9R1
R 1
J 0
(2250 2975);
DISPLAY 0.617021 (2250 2975);
PAINT AQUA (2250 2975);
DISPLAY INVISIBLE (2250 2975);
FORCEPROP 1 LAST PATH I57
R 1
J 0
(2200 2975);
DISPLAY 0.978723 (2200 2975);
PAINT WHITE (2200 2975);
DISPLAY INVISIBLE (2200 2975);
FORCEPROP 0 LAST ROOM HOT_SWAP
R 1
J 0
(2150 2975);
DISPLAY 1.021277 (2150 2975);
PAINT ORANGE (2150 2975);
DISPLAY INVISIBLE (2150 2975);
FORCEPROP 1 LAST PACK_TYPE SOT5
R 1
J 0
(2400 2975);
DISPLAY 0.957447 (2400 2975);
PAINT SKYBLUE (2400 2975);
DISPLAY INVISIBLE (2400 2975);
FORCEPROP 2 LAST SEC_TYPE SOT5
J 0
(2350 3025);
DISPLAY 1.021277 (2350 3025);
PAINT ORANGE (2350 3025);
DISPLAY INVISIBLE (2350 3025);
FORCEPROP 2 LAST SEC 1
J 0
(2350 3025);
DISPLAY 0.680851 (2350 3025);
PAINT MONO (2350 3025);
DISPLAY INVISIBLE (2350 3025);
FORCEADD RES..1
(2000 2525);
FORCEPROP 1 LAST PACK_TYPE 0402
J 0
(1825 2475);
DISPLAY 0.617021 (1825 2475);
PAINT SKYBLUE (1825 2475);
FORCEPROP 1 LAST VALUE 10.0
J 2
(2025 2475);
DISPLAY 0.617021 (2025 2475);
PAINT SKYBLUE (2025 2475);
FORCEPROP 1 LAST TOLERANCE 1%
J 0
(2075 2475);
DISPLAY 0.617021 (2075 2475);
PAINT SKYBLUE (2075 2475);
FORCEPROP 1 LAST PART_NUMBER G21796-066
J 0
(1950 2625);
DISPLAY 0.617021 (1950 2625);
PAINT BLUE (1950 2625);
FORCEPROP 1 LAST MATERIAL CHIP
J 0
(1825 2375);
DISPLAY 0.617021 (1825 2375);
PAINT SKYBLUE (1825 2375);
FORCEPROP 1 LAST LOCATION R9R4
J 0
(1950 2575);
DISPLAY 0.617021 (1950 2575);
PAINT AQUA (1950 2575);
FORCEPROP 1 LAST WATTAGE 1/16W
J 2
(1950 2425);
DISPLAY 0.617021 (1950 2425);
PAINT SKYBLUE (1950 2425);
FORCEPROP 1 LASTPIN (1900 2525) $PN 1
J 0
(1912 2537);
DISPLAY 0.787234 (1912 2537);
PAINT ORANGE (1912 2537);
DISPLAY INVISIBLE (1912 2537);
FORCEPROP 2 LAST CDS_LIB mstr_discrete
J 0
(2000 2525);
PAINT ORANGE (2000 2525);
DISPLAY INVISIBLE (2000 2525);
FORCEPROP 2 LAST CDS_SEC 1
J 0
(1950 2725);
DISPLAY 1.021277 (1950 2725);
PAINT ORANGE (1950 2725);
DISPLAY INVISIBLE (1950 2725);
FORCEPROP 1 LAST PATH I58
J 0
(1950 2675);
DISPLAY 0.978723 (1950 2675);
PAINT WHITE (1950 2675);
DISPLAY INVISIBLE (1950 2675);
FORCEPROP 2 LAST CDS_LOCATION R9R4
J 0
(1950 2575);
DISPLAY 0.617021 (1950 2575);
PAINT AQUA (1950 2575);
DISPLAY INVISIBLE (1950 2575);
FORCEPROP 2 LAST $SEC 1
J 0
(1950 2725);
DISPLAY 0.680851 (1950 2725);
PAINT MONO (1950 2725);
DISPLAY INVISIBLE (1950 2725);
FORCEPROP 0 LAST ROOM HOT_SWAP
J 0
(1950 2725);
DISPLAY 1.021277 (1950 2725);
PAINT ORANGE (1950 2725);
DISPLAY INVISIBLE (1950 2725);
FORCEPROP 1 LASTPIN (2100 2525) $PN 2
J 0
(2062 2537);
DISPLAY 0.787234 (2062 2537);
PAINT ORANGE (2062 2537);
DISPLAY INVISIBLE (2062 2537);
FORCEADD MOSFETN_1D3S..1
R 1
(2275 2100);
FORCEPROP 1 LAST LOCATION EU1E1
R 1
J 0
(2225 2250);
DISPLAY 0.617021 (2225 2250);
PAINT AQUA (2225 2250);
FORCEPROP 1 LAST PART_NUMBER G68777-001
J 0
(2275 2325);
DISPLAY 0.617021 (2275 2325);
PAINT BLUE (2275 2325);
FORCEPROP 2 LASTPIN (2425 2100) $PN 2
J 0
(2435 2110);
DISPLAY 0.617021 (2435 2110);
PAINT ORANGE (2435 2110);
FORCEPROP 2 LASTPIN (2325 1900) $PN 4
R 1
J 2
(2315 1890);
DISPLAY 0.617021 (2315 1890);
PAINT ORANGE (2315 1890);
FORCEPROP 2 LASTPIN (2425 2050) $PN 1
J 0
(2435 2060);
DISPLAY 0.617021 (2435 2060);
PAINT ORANGE (2435 2060);
FORCEPROP 2 LASTPIN (2425 2150) $PN 3
J 0
(2435 2160);
DISPLAY 0.617021 (2435 2160);
PAINT ORANGE (2435 2160);
FORCEPROP 2 LASTPIN (2125 2050) $PN 5
J 2
(2115 2060);
DISPLAY 0.617021 (2115 2060);
PAINT ORANGE (2115 2060);
FORCEPROP 1 LAST MATERIAL IC
R 1
J 0
(2275 2250);
DISPLAY 0.617021 (2275 2250);
PAINT SKYBLUE (2275 2250);
FORCEPROP 2 LAST CDS_LIB mstr_discrete
J 0
(2275 2100);
PAINT ORANGE (2275 2100);
DISPLAY INVISIBLE (2275 2100);
FORCEPROP 2 LAST CDS_LOCATION EU1E1
R 1
J 0
(2225 2250);
DISPLAY 0.617021 (2225 2250);
PAINT AQUA (2225 2250);
DISPLAY INVISIBLE (2225 2250);
FORCEPROP 1 LAST PATH I59
R 1
J 0
(2175 2250);
DISPLAY 0.978723 (2175 2250);
PAINT WHITE (2175 2250);
DISPLAY INVISIBLE (2175 2250);
FORCEPROP 0 LAST ROOM HOT_SWAP
R 1
J 0
(2125 2250);
DISPLAY 1.021277 (2125 2250);
PAINT ORANGE (2125 2250);
DISPLAY INVISIBLE (2125 2250);
FORCEPROP 1 LAST PACK_TYPE SOT5
R 1
J 0
(2375 2250);
DISPLAY 0.957447 (2375 2250);
PAINT SKYBLUE (2375 2250);
DISPLAY INVISIBLE (2375 2250);
FORCEPROP 2 LAST SEC_TYPE SOT5
J 0
(2325 2300);
DISPLAY 1.021277 (2325 2300);
PAINT ORANGE (2325 2300);
DISPLAY INVISIBLE (2325 2300);
FORCEPROP 2 LAST SEC 1
J 0
(2325 2300);
DISPLAY 0.680851 (2325 2300);
PAINT MONO (2325 2300);
DISPLAY INVISIBLE (2325 2300);
FORCEADD RES..1
(1950 1775);
FORCEPROP 1 LAST PART_NUMBER G21796-066
J 0
(1900 1875);
DISPLAY 0.617021 (1900 1875);
PAINT BLUE (1900 1875);
FORCEPROP 1 LASTPIN (2050 1775) $PN 2
J 0
(2012 1787);
DISPLAY 0.617021 (2012 1787);
PAINT ORANGE (2012 1787);
FORCEPROP 1 LAST LOCATION R1D48
J 0
(1900 1825);
DISPLAY 0.617021 (1900 1825);
PAINT AQUA (1900 1825);
FORCEPROP 1 LAST TOLERANCE 1%
J 0
(2025 1725);
DISPLAY 0.617021 (2025 1725);
PAINT SKYBLUE (2025 1725);
FORCEPROP 1 LASTPIN (1850 1775) $PN 1
J 0
(1862 1787);
DISPLAY 0.617021 (1862 1787);
PAINT ORANGE (1862 1787);
FORCEPROP 1 LAST VALUE 10.0
J 2
(1975 1725);
DISPLAY 0.617021 (1975 1725);
PAINT SKYBLUE (1975 1725);
FORCEPROP 1 LAST PACK_TYPE 0402
J 0
(1725 1725);
DISPLAY 0.617021 (1725 1725);
PAINT SKYBLUE (1725 1725);
FORCEPROP 1 LAST MATERIAL CHIP
J 0
(1750 1625);
DISPLAY 0.617021 (1750 1625);
PAINT SKYBLUE (1750 1625);
FORCEPROP 1 LAST WATTAGE 1/16W
J 2
(1850 1675);
DISPLAY 0.617021 (1850 1675);
PAINT SKYBLUE (1850 1675);
FORCEPROP 0 LAST ROOM HOT_SWAP
J 0
(1900 1975);
DISPLAY 1.021277 (1900 1975);
PAINT ORANGE (1900 1975);
DISPLAY INVISIBLE (1900 1975);
FORCEPROP 2 LAST CDS_LOCATION R1D48
J 0
(1900 1825);
DISPLAY 0.617021 (1900 1825);
PAINT AQUA (1900 1825);
DISPLAY INVISIBLE (1900 1825);
FORCEPROP 2 LAST SEC 1
J 0
(1900 1975);
DISPLAY 0.680851 (1900 1975);
PAINT MONO (1900 1975);
DISPLAY INVISIBLE (1900 1975);
FORCEPROP 2 LAST SEC_TYPE 0402
J 0
(1900 1975);
DISPLAY 1.021277 (1900 1975);
PAINT ORANGE (1900 1975);
DISPLAY INVISIBLE (1900 1975);
FORCEPROP 2 LAST CDS_LIB mstr_discrete
J 0
(1950 1775);
PAINT ORANGE (1950 1775);
DISPLAY INVISIBLE (1950 1775);
FORCEPROP 1 LAST PATH I60
J 0
(1900 1925);
DISPLAY 0.978723 (1900 1925);
PAINT WHITE (1900 1925);
DISPLAY INVISIBLE (1900 1925);
FORCEADD P12V_STBY..1
(2525 3800);
FORCEPROP 3 LASTPIN (2525 3750) SIG_NAME P12V_STBY\g
J 0
(2535 3760);
DISPLAY 0.659574 (2535 3760);
PAINT MONO (2535 3760);
DISPLAY INVISIBLE (2535 3760);
FORCEPROP 1 LAST VOLTAGE 12.0V
J 0
(2480 3757);
DISPLAY 0.340426 (2480 3757);
PAINT SKYBLUE (2480 3757);
DISPLAY INVISIBLE (2480 3757);
FORCEPROP 2 LAST CDS_LIB mstr_symbols
J 0
(2525 3800);
PAINT ORANGE (2525 3800);
DISPLAY INVISIBLE (2525 3800);
FORCEPROP 1 LAST PATH I64
J 0
(2570 3802);
DISPLAY 0.340426 (2570 3802);
PAINT GREEN (2570 3802);
DISPLAY INVISIBLE (2570 3802);
FORCEPROP 1 LAST SIZE 1B
J 0
(2570 3822);
DISPLAY 0.340426 (2570 3822);
PAINT GREEN (2570 3822);
DISPLAY INVISIBLE (2570 3822);
FORCEPROP 1 LAST BODY_TYPE PLUMBING
J 0
(2480 3757);
DISPLAY 0.340426 (2480 3757);
PAINT GREEN (2480 3757);
DISPLAY INVISIBLE (2480 3757);
FORCEPROP 1 LAST HDL_POWER P12V_STBY
J 0
(2225 3675);
DISPLAY 0.872340 (2225 3675);
PAINT ORANGE (2225 3675);
DISPLAY INVISIBLE (2225 3675);
FORCEADD RES..2
(-4400 -400);
FORCEPROP 1 LAST PACK_TYPE 0402
J 0
(-4360 -575);
DISPLAY 0.617021 (-4360 -575);
PAINT SKYBLUE (-4360 -575);
FORCEPROP 1 LASTPIN (-4400 -500) $PN 2
J 0
(-4395 -490);
DISPLAY 0.617021 (-4395 -490);
PAINT ORANGE (-4395 -490);
FORCEPROP 1 LASTPIN (-4400 -300) $PN 1
J 0
(-4395 -338);
DISPLAY 0.617021 (-4395 -338);
PAINT ORANGE (-4395 -338);
FORCEPROP 1 LAST WATTAGE 1/16W
J 0
(-4360 -425);
DISPLAY 0.617021 (-4360 -425);
PAINT SKYBLUE (-4360 -425);
FORCEPROP 1 LAST TOLERANCE 1%
J 0
(-4355 -375);
DISPLAY 0.617021 (-4355 -375);
PAINT SKYBLUE (-4355 -375);
FORCEPROP 1 LAST VALUE 10.0K
J 0
(-4355 -325);
DISPLAY 0.617021 (-4355 -325);
PAINT SKYBLUE (-4355 -325);
FORCEPROP 1 LAST LOCATION R9P19
J 0
(-4355 -275);
DISPLAY 0.617021 (-4355 -275);
PAINT AQUA (-4355 -275);
FORCEPROP 1 LAST MATERIAL EMPTY
J 0
(-4360 -475);
DISPLAY 0.617021 (-4360 -475);
PAINT RED (-4360 -475);
FORCEPROP 1 LAST PART_NUMBER G21796-016
J 0
(-4360 -525);
DISPLAY 0.617021 (-4360 -525);
PAINT BLUE (-4360 -525);
FORCEPROP 2 LAST CDS_LIB mstr_discrete
J 0
(-4400 -400);
PAINT ORANGE (-4400 -400);
DISPLAY INVISIBLE (-4400 -400);
FORCEPROP 2 LAST CDS_LOCATION R9P19
J 0
(-4355 -275);
DISPLAY 0.617021 (-4355 -275);
PAINT AQUA (-4355 -275);
DISPLAY INVISIBLE (-4355 -275);
FORCEPROP 2 LAST ROOM HOT_SWAP
J 0
(-4350 -225);
DISPLAY 1.021277 (-4350 -225);
PAINT ORANGE (-4350 -225);
DISPLAY INVISIBLE (-4350 -225);
FORCEPROP 1 LAST PATH I70
J 0
(-4350 -225);
DISPLAY 0.978723 (-4350 -225);
PAINT WHITE (-4350 -225);
DISPLAY INVISIBLE (-4350 -225);
FORCEPROP 2 LAST SEC 1
J 0
(-4350 -175);
DISPLAY 0.680851 (-4350 -175);
PAINT MONO (-4350 -175);
DISPLAY INVISIBLE (-4350 -175);
FORCEPROP 2 LAST SEC_TYPE 0402
J 0
(-4350 -175);
DISPLAY 1.021277 (-4350 -175);
PAINT ORANGE (-4350 -175);
DISPLAY INVISIBLE (-4350 -175);
FORCEADD RES..2
(-4400 250);
FORCEPROP 1 LAST PACK_TYPE 0402
J 0
(-4535 300);
DISPLAY 0.617021 (-4535 300);
PAINT SKYBLUE (-4535 300);
FORCEPROP 1 LASTPIN (-4400 150) $PN 2
J 0
(-4395 160);
DISPLAY 0.617021 (-4395 160);
PAINT ORANGE (-4395 160);
FORCEPROP 1 LASTPIN (-4400 350) $PN 1
J 0
(-4395 312);
DISPLAY 0.617021 (-4395 312);
PAINT ORANGE (-4395 312);
FORCEPROP 1 LAST VALUE 0.0
J 0
(-4355 325);
DISPLAY 0.617021 (-4355 325);
PAINT SKYBLUE (-4355 325);
FORCEPROP 1 LAST LOCATION R9P21
J 0
(-4355 375);
DISPLAY 0.617021 (-4355 375);
PAINT AQUA (-4355 375);
FORCEPROP 1 LAST TOLERANCE 5%
J 0
(-4355 275);
DISPLAY 0.617021 (-4355 275);
PAINT SKYBLUE (-4355 275);
FORCEPROP 1 LAST PART_NUMBER G21497-005
J 0
(-4360 125);
DISPLAY 0.617021 (-4360 125);
PAINT BLUE (-4360 125);
FORCEPROP 1 LAST WATTAGE 1/16W
J 0
(-4360 225);
DISPLAY 0.617021 (-4360 225);
PAINT SKYBLUE (-4360 225);
FORCEPROP 1 LAST MATERIAL CHIP
J 0
(-4360 175);
DISPLAY 0.617021 (-4360 175);
PAINT SKYBLUE (-4360 175);
FORCEPROP 2 LAST CDS_LIB mstr_discrete
J 0
(-4400 250);
PAINT ORANGE (-4400 250);
DISPLAY INVISIBLE (-4400 250);
FORCEPROP 2 LAST CDS_LOCATION R9P21
J 0
(-4355 375);
DISPLAY 0.617021 (-4355 375);
PAINT AQUA (-4355 375);
DISPLAY INVISIBLE (-4355 375);
FORCEPROP 2 LAST SEC 1
J 0
(-4350 475);
DISPLAY 0.680851 (-4350 475);
PAINT MONO (-4350 475);
DISPLAY INVISIBLE (-4350 475);
FORCEPROP 1 LAST PATH I71
J 0
(-4350 425);
DISPLAY 0.978723 (-4350 425);
PAINT WHITE (-4350 425);
DISPLAY INVISIBLE (-4350 425);
FORCEPROP 2 LAST ROOM HOT_SWAP
J 0
(-4350 425);
DISPLAY 1.021277 (-4350 425);
PAINT ORANGE (-4350 425);
DISPLAY INVISIBLE (-4350 425);
FORCEPROP 2 LAST SEC_TYPE 0402
J 0
(-4350 475);
DISPLAY 1.021277 (-4350 475);
PAINT ORANGE (-4350 475);
DISPLAY INVISIBLE (-4350 475);
FORCEADD OFFPAGE..1
(-4700 525);
FORCEPROP 2 LAST $XR0 199 
J 0
(-4952 525);
DISPLAY 0.638298 (-4952 525);
PAINT MONO (-4952 525);
FORCEPROP 2 LAST PATH I72
J 0
(-4950 575);
DISPLAY 1.021277 (-4950 575);
PAINT ORANGE (-4950 575);
DISPLAY INVISIBLE (-4950 575);
FORCEPROP 2 LAST CDS_LIB mstr_standard
J 0
(-4700 525);
PAINT ORANGE (-4700 525);
DISPLAY INVISIBLE (-4700 525);
FORCEPROP 1 LAST OFFPAGE TRUE
J 0
(-4375 400);
DISPLAY 0.872340 (-4375 400);
PAINT GREEN (-4375 400);
DISPLAY INVISIBLE (-4375 400);
FORCEPROP 1 LAST COMMENT_BODY TRUE
J 0
(-4575 425);
DISPLAY 0.872340 (-4575 425);
PAINT GREEN (-4575 425);
DISPLAY INVISIBLE (-4575 425);
FORCEADD P3V3_STBY..1
(-3300 800);
FORCEPROP 3 LASTPIN (-3300 750) SIG_NAME P3V3_STBY\g
J 0
(-3290 760);
DISPLAY 0.659574 (-3290 760);
PAINT MONO (-3290 760);
DISPLAY INVISIBLE (-3290 760);
FORCEPROP 1 LAST VOLTAGE 3.3V
J 0
(-3345 757);
DISPLAY 0.340426 (-3345 757);
PAINT SKYBLUE (-3345 757);
DISPLAY INVISIBLE (-3345 757);
FORCEPROP 1 LAST SIZE 1B
J 0
(-3255 822);
DISPLAY 0.340426 (-3255 822);
PAINT GREEN (-3255 822);
DISPLAY INVISIBLE (-3255 822);
FORCEPROP 2 LAST CDS_LIB mstr_symbols
J 0
(-3300 800);
PAINT ORANGE (-3300 800);
DISPLAY INVISIBLE (-3300 800);
FORCEPROP 1 LAST PATH I78
J 0
(-3255 802);
DISPLAY 0.340426 (-3255 802);
PAINT GREEN (-3255 802);
DISPLAY INVISIBLE (-3255 802);
FORCEPROP 1 LAST BODY_TYPE PLUMBING
J 0
(-3345 757);
DISPLAY 0.340426 (-3345 757);
PAINT GREEN (-3345 757);
DISPLAY INVISIBLE (-3345 757);
FORCEPROP 1 LAST HDL_POWER P3V3_STBY
J 0
(-3600 675);
DISPLAY 0.872340 (-3600 675);
PAINT ORANGE (-3600 675);
DISPLAY INVISIBLE (-3600 675);
FORCEADD RES..2
(-3300 450);
FORCEPROP 1 LAST LOCATION R9P20
J 0
(-3255 575);
DISPLAY 0.617021 (-3255 575);
PAINT AQUA (-3255 575);
FORCEPROP 1 LAST WATTAGE 1/16W
J 0
(-3260 425);
DISPLAY 0.617021 (-3260 425);
PAINT SKYBLUE (-3260 425);
FORCEPROP 1 LASTPIN (-3300 350) $PN 2
J 0
(-3295 360);
DISPLAY 0.617021 (-3295 360);
PAINT ORANGE (-3295 360);
FORCEPROP 1 LAST MATERIAL CHIP
J 0
(-3260 375);
DISPLAY 0.617021 (-3260 375);
PAINT SKYBLUE (-3260 375);
FORCEPROP 1 LAST PACK_TYPE 0402
J 0
(-3135 375);
DISPLAY 0.617021 (-3135 375);
PAINT SKYBLUE (-3135 375);
FORCEPROP 1 LAST TOLERANCE 1%
J 0
(-3255 475);
DISPLAY 0.617021 (-3255 475);
PAINT SKYBLUE (-3255 475);
FORCEPROP 1 LAST PART_NUMBER G21796-344
J 0
(-3260 325);
DISPLAY 0.617021 (-3260 325);
PAINT BLUE (-3260 325);
FORCEPROP 1 LASTPIN (-3300 550) $PN 1
J 0
(-3295 512);
DISPLAY 0.617021 (-3295 512);
PAINT ORANGE (-3295 512);
FORCEPROP 1 LAST VALUE 2.7K
J 0
(-3255 525);
DISPLAY 0.617021 (-3255 525);
PAINT SKYBLUE (-3255 525);
FORCEPROP 2 LAST CDS_LIB mstr_discrete
J 0
(-3300 450);
PAINT ORANGE (-3300 450);
DISPLAY INVISIBLE (-3300 450);
FORCEPROP 2 LAST CDS_LOCATION R9P20
J 0
(-3255 575);
DISPLAY 0.617021 (-3255 575);
PAINT AQUA (-3255 575);
DISPLAY INVISIBLE (-3255 575);
FORCEPROP 1 LAST PATH I86
J 0
(-3250 625);
DISPLAY 0.978723 (-3250 625);
PAINT WHITE (-3250 625);
DISPLAY INVISIBLE (-3250 625);
FORCEPROP 2 LAST ROOM HOT_SWAP
J 0
(-3250 625);
DISPLAY 1.021277 (-3250 625);
PAINT ORANGE (-3250 625);
DISPLAY INVISIBLE (-3250 625);
FORCEPROP 2 LAST SEC_TYPE 0402
J 0
(-3250 675);
DISPLAY 1.021277 (-3250 675);
PAINT ORANGE (-3250 675);
DISPLAY INVISIBLE (-3250 675);
FORCEPROP 2 LAST SEC 1
J 0
(-3250 675);
DISPLAY 0.680851 (-3250 675);
PAINT MONO (-3250 675);
DISPLAY INVISIBLE (-3250 675);
FORCEADD OFFPAGE..2
(-2550 300);
FORCEPROP 2 LAST $XR2 170 
J 0
(-2121 300);
DISPLAY 0.638298 (-2121 300);
PAINT MONO (-2121 300);
FORCEPROP 2 LAST $XR1 145 
J 0
(-2241 300);
DISPLAY 0.638298 (-2241 300);
PAINT MONO (-2241 300);
FORCEPROP 2 LAST $XR0 120 
J 0
(-2361 300);
DISPLAY 0.638298 (-2361 300);
PAINT MONO (-2361 300);
FORCEPROP 2 LAST PATH I92
J 0
(-2500 375);
DISPLAY 1.021277 (-2500 375);
PAINT ORANGE (-2500 375);
DISPLAY INVISIBLE (-2500 375);
FORCEPROP 2 LAST CDS_LIB mstr_standard
J 0
(-2550 300);
PAINT ORANGE (-2550 300);
DISPLAY INVISIBLE (-2550 300);
FORCEPROP 1 LAST OFFPAGE TRUE
J 0
(-2225 175);
DISPLAY 0.872340 (-2225 175);
PAINT GREEN (-2225 175);
DISPLAY INVISIBLE (-2225 175);
FORCEPROP 1 LAST COMMENT_BODY TRUE
J 0
(-2595 205);
DISPLAY 0.872340 (-2595 205);
PAINT GREEN (-2595 205);
DISPLAY INVISIBLE (-2595 205);
FORCEADD OFFPAGE..1
(-4675 3675);
FORCEPROP 2 LAST $XR0 199 
J 0
(-4957 3675);
DISPLAY 0.638298 (-4957 3675);
PAINT MONO (-4957 3675);
FORCEPROP 2 LAST PATH I94
J 0
(-4625 3750);
DISPLAY 1.021277 (-4625 3750);
PAINT ORANGE (-4625 3750);
DISPLAY INVISIBLE (-4625 3750);
FORCEPROP 2 LAST CDS_LIB mstr_standard
J 0
(-4675 3675);
PAINT ORANGE (-4675 3675);
DISPLAY INVISIBLE (-4675 3675);
FORCEPROP 1 LAST OFFPAGE TRUE
J 0
(-4350 3550);
DISPLAY 0.872340 (-4350 3550);
PAINT GREEN (-4350 3550);
DISPLAY INVISIBLE (-4350 3550);
FORCEPROP 1 LAST COMMENT_BODY TRUE
J 0
(-4550 3575);
DISPLAY 0.872340 (-4550 3575);
PAINT GREEN (-4550 3575);
DISPLAY INVISIBLE (-4550 3575);
FORCEADD DNS..2
(-4395 -405);
PAINT RED (-4395 -405);
FORCEPROP 2 LAST CDS_LIB mstr_misc
J 0
(-4395 -405);
PAINT ORANGE (-4395 -405);
DISPLAY INVISIBLE (-4395 -405);
FORCEPROP 1 LAST COMMENT_BODY TRUE
R 1
J 0
(-4320 -630);
DISPLAY 0.872340 (-4320 -630);
PAINT GREEN (-4320 -630);
DISPLAY INVISIBLE (-4320 -630);
FORCEADD INTEL_CORP_BPAGE..1
(3000 -875);
FORCEPROP 1 LAST CDS_CON_LAST_MODIFIED Fri Jun 16 17:49:13 2017
J 0
(1575 -550);
PAINT GREEN (1575 -550);
DISPLAY INVISIBLE (1575 -550);
FORCEPROP 1 LAST CUSTOM_TXT_CDS <CURRENT_DESIGN_SHEET> OF <TOTAL_DESIGN_SHEETS>
J 0
(2500 -850);
PAINT ORANGE (2500 -850);
FORCEPROP 1 LAST CUSTOM_TXT_CDS <CON_LAST_MODIFIED>
J 0
(-1000 -775);
PAINT ORANGE (-1000 -775);
FORCEPROP 2 LAST CUSTOM_TXT_CDS <XR_PAGE_TITLE>
J 0
(-4890 4375);
DISPLAY 0.638298 (-4890 4375);
PAINT PINK (-4890 4375);
DISPLAY INVISIBLE (-4890 4375);
FORCEPROP 1 LAST SCH_TITLE HOT SWAP CONTROLLER (2/2)
J 0
(-4950 -825);
DISPLAY 1.212766 (-4950 -825);
PAINT ORANGE (-4950 -825);
FORCEPROP 2 LAST BOM_COST MISC_POWER
J 0
(-4875 4425);
DISPLAY 1.382979 (-4875 4425);
PAINT ORANGE (-4875 4425);
DISPLAY INVISIBLE (-4875 4425);
FORCEPROP 2 LAST PAGE_BORDER TRUE
J 0
(-4890 4375);
DISPLAY 1.021277 (-4890 4375);
PAINT PINK (-4890 4375);
DISPLAY INVISIBLE (-4890 4375);
FORCEPROP 2 LAST CDS_LIB mstr_symbols
J 0
(3000 -875);
PAINT ORANGE (3000 -875);
DISPLAY INVISIBLE (3000 -875);
FORCEPROP 2 LAST ROOM S3_SWITCH
J 0
(2550 4275);
PAINT ORANGE (2550 4275);
DISPLAY INVISIBLE (2550 4275);
FORCEPROP 1 LAST COMMENT_BODY TRUE
J 0
(3012 -863);
DISPLAY 0.468085 (3012 -863);
PAINT GREEN (3012 -863);
DISPLAY INVISIBLE (3012 -863);
FORCEPROP 2 LAST CDS_XR_PAGE_TITLE CR-200 : @BASEBOARD_FAB2_LIB.BASEBOARD_FAB2(SCH_1):PAGE200
J 0
(-4890 4375);
DISPLAY 0.638298 (-4890 4375);
PAINT PINK (-4890 4375);
DISPLAY INVISIBLE (-4890 4375);
FORCEADD DNS..2
(2755 3270);
PAINT RED (2755 3270);
FORCEPROP 2 LAST CDS_LIB mstr_misc
J 0
(2755 3270);
PAINT ORANGE (2755 3270);
DISPLAY INVISIBLE (2755 3270);
FORCEPROP 1 LAST COMMENT_BODY TRUE
R 1
J 0
(2830 3045);
DISPLAY 0.872340 (2830 3045);
PAINT GREEN (2830 3045);
DISPLAY INVISIBLE (2830 3045);
FORCEADD DNS..2
(-670 2995);
PAINT RED (-670 2995);
FORCEPROP 2 LAST CDS_LIB mstr_misc
J 0
(-670 2995);
PAINT ORANGE (-670 2995);
DISPLAY INVISIBLE (-670 2995);
FORCEPROP 1 LAST COMMENT_BODY TRUE
R 1
J 0
(-595 2770);
DISPLAY 0.872340 (-595 2770);
PAINT GREEN (-595 2770);
DISPLAY INVISIBLE (-595 2770);
FORCEADD DNS..2
(-1020 3420);
PAINT RED (-1020 3420);
FORCEPROP 2 LAST CDS_LIB mstr_misc
J 0
(-1020 3420);
PAINT ORANGE (-1020 3420);
DISPLAY INVISIBLE (-1020 3420);
FORCEPROP 1 LAST COMMENT_BODY TRUE
R 1
J 0
(-945 3195);
DISPLAY 0.872340 (-945 3195);
PAINT GREEN (-945 3195);
DISPLAY INVISIBLE (-945 3195);
FORCEADD DNS..2
(-170 3420);
PAINT RED (-170 3420);
FORCEPROP 2 LAST CDS_LIB mstr_misc
J 0
(-170 3420);
PAINT ORANGE (-170 3420);
DISPLAY INVISIBLE (-170 3420);
FORCEPROP 1 LAST COMMENT_BODY TRUE
R 1
J 0
(-95 3195);
DISPLAY 0.872340 (-95 3195);
PAINT GREEN (-95 3195);
DISPLAY INVISIBLE (-95 3195);
WIRE 16 -1 (-1650 -300)(-1650 -250);
WIRE 16 -1 (-1650 475)(-1650 400);
WIRE 16 -1 (-3075 -425)(-3075 -300);
WIRE 16 -1 (-3075 -300)(-3125 -300);
WIRE 16 -1 (-1975 1000)(-1975 1025);
WIRE 16 -1 (-1125 1000)(-1975 1000);
WIRE 16 -1 (-1975 900)(-1975 1000);
WIRE 16 -1 (-1125 450)(-1125 1000);
WIRE 16 -1 (-825 1000)(-1125 1000);
WIRE 16 -1 (-825 875)(-825 1000);
WIRE 16 -1 (-650 450)(-1125 450);
WIRE 16 -1 (-1975 225)(-1975 275);
WIRE 16 -1 (600 1250)(600 1200);
WIRE 16 -1 (900 1575)(900 1500);
WIRE 16 -1 (-1650 2450)(-1650 2475);
WIRE 16 -1 (-50 100)(-50 200);
WIRE 16 -1 (550 -350)(550 -300);
WIRE 16 -1 (-4150 2350)(-4150 2275);
WIRE 16 -1 (-4575 2775)(-4575 2550);
WIRE 16 -1 (-2750 2975)(-2750 2850);
WIRE 16 -1 (-2800 2975)(-2750 2975);
WIRE 16 -1 (-3800 3650)(-3800 3600);
WIRE 16 -1 (-3650 3600)(-3800 3600);
WIRE 16 -1 (-3800 3525)(-3800 3600);
WIRE 16 -1 (-3650 3225)(-3650 3600);
WIRE 16 -1 (-3400 3225)(-3650 3225);
WIRE 16 -1 (-3800 3325)(-3800 3225);
WIRE 16 -1 (-2600 3750)(-2600 3800);
WIRE 16 -1 (-2950 3750)(-2600 3750);
WIRE 16 -1 (-2600 3650)(-2600 3750);
WIRE 16 -1 (-2950 3650)(-2950 3750);
WIRE 16 -1 (275 1175)(275 1250);
WIRE 16 -1 (-2000 3075)(-2000 3125);
WIRE 16 -1 (-3450 400)(-3450 275);
WIRE 16 -1 (-3500 1850)(-3500 1900);
WIRE 16 -1 (-3500 1100)(-3500 975);
WIRE 16 -1 (1750 325)(1750 400);
WIRE 16 -1 (1500 1350)(1500 1225);
WIRE 16 -1 (-4400 -600)(-4400 -500);
WIRE 16 -1 (-3950 -575)(-3950 -625);
WIRE 16 -1 (2750 3175)(2750 3050);
WIRE 16 -1 (-3950 650)(-3950 300);
WIRE 16 -1 (-1500 1475)(-1500 1350);
WIRE 16 -1 (-700 -200)(-700 -175);
WIRE 16 -1 (-1050 -50)(-1050 100);
WIRE 16 -1 (-1025 3325)(-1025 3275);
WIRE 16 -1 (-675 2900)(-675 2775);
WIRE 16 -1 (900 3775)(900 3650);
WIRE 16 -1 (900 3550)(900 3650);
WIRE 16 -1 (900 3650)(1025 3650);
WIRE 16 -1 (900 3250)(900 3550);
WIRE 16 -1 (900 3550)(1025 3550);
WIRE 16 -1 (900 3250)(900 3150);
WIRE 16 -1 (1025 3250)(900 3250);
WIRE 16 -1 (900 3150)(1025 3150);
WIRE 16 -1 (2525 3750)(2525 3700);
WIRE 16 -1 (2525 3425)(2525 3700);
WIRE 16 -1 (2525 3700)(2750 3700);
WIRE 16 -1 (2750 3700)(2750 3375);
WIRE 16 -1 (2525 3425)(2525 3375);
WIRE 16 -1 (2425 3425)(2525 3425);
WIRE 16 -1 (2525 3375)(2525 3325);
WIRE 16 -1 (2525 3375)(2425 3375);
WIRE 16 -1 (2525 3325)(2525 2875);
WIRE 16 -1 (2525 3325)(2425 3325);
WIRE 16 -1 (2525 2875)(2525 2825);
WIRE 16 -1 (2525 2875)(2450 2875);
WIRE 16 -1 (2525 2825)(2525 2775);
WIRE 16 -1 (2525 2825)(2450 2825);
WIRE 16 -1 (2525 2775)(2525 2150);
WIRE 16 -1 (2525 2775)(2450 2775);
WIRE 16 -1 (2525 2150)(2525 2100);
WIRE 16 -1 (2525 2150)(2425 2150);
WIRE 16 -1 (2525 2050)(2525 2100);
WIRE 16 -1 (2525 2100)(2425 2100);
WIRE 16 -1 (2525 2050)(2425 2050);
WIRE 16 -1 (-3300 750)(-3300 675);
WIRE 16 -1 (-3300 675)(-3450 675);
WIRE 16 -1 (-3300 675)(-3300 550);
WIRE 16 -1 (-3450 675)(-3800 675);
WIRE 16 -1 (-3450 600)(-3450 675);
WIRE 16 -1 (-3800 -50)(-3800 675);
WIRE 16 -1 (-3725 -50)(-3800 -50);
WIRE 16 -1 (-3400 3075)(-4575 3075);
FORCEPROP 0 LAST SIG_NAME A_HSC_LOW
J 0
(-4547 3097);
DISPLAY 0.617021 (-4547 3097);
PAINT ORANGE (-4547 3097);
FORCEPROP 2 LASTPROP $XRERR UNIQUE?
J 0
(-4787 3097);
DISPLAY 0.638298 (-4787 3097);
PAINT MONO (-4787 3097);
DISPLAY INVISIBLE (-4787 3097);
WIRE 16 -1 (-4575 2975)(-4575 3075);
WIRE 16 -1 (-4575 3075)(-4575 3350);
WIRE 3 682 (-4975 2150)(-4975 3750);
WIRE 3 682 (-3700 2150)(-4975 2150);
WIRE 3 682 (-4975 3750)(-4050 3750);
WIRE 3 682 (-4050 3750)(-4050 3000);
WIRE 3 682 (-3700 2300)(-3700 2150);
WIRE 3 682 (-3850 2300)(-3700 2300);
WIRE 3 682 (-4050 3000)(-3850 3000);
WIRE 3 682 (-3850 3000)(-3850 2300);
WIRE 16 -1 (1775 2050)(2125 2050);
WIRE 16 -1 (1225 3150)(1300 3150);
WIRE 16 -1 (1225 3650)(1300 3650);
WIRE 16 -1 (1225 3550)(1300 3550);
WIRE 16 -1 (1300 3650)(1300 3550);
WIRE 16 -1 (1225 3250)(1300 3250);
WIRE 16 -1 (1300 3150)(1300 3250);
WIRE 16 -1 (1775 2775)(1775 2050);
WIRE 16 -1 (1775 2775)(2150 2775);
WIRE 16 -1 (1775 3325)(1775 2775);
WIRE 16 -1 (2125 3325)(1775 3325);
WIRE 16 -1 (1300 3250)(1300 3325);
WIRE 16 -1 (1300 3550)(1300 3325);
WIRE 16 -1 (1300 3325)(1775 3325);
FORCEPROP 0 LAST VOLTAGE +12V
J 0
(1450 3400);
DISPLAY 1.021277 (1450 3400);
PAINT SKYBLUE (1450 3400);
DISPLAY INVISIBLE (1450 3400);
FORCEPROP 0 LAST SIG_NAME P12V_MB0_SW
J 0
(1565 3335);
DISPLAY 0.617021 (1565 3335);
PAINT ORANGE (1565 3335);
FORCEPROP 2 LASTPROP $XRERR UNIQUE?
J 0
(1325 3335);
DISPLAY 0.638298 (1325 3335);
PAINT MONO (1325 3335);
DISPLAY INVISIBLE (1325 3335);
WIRE 3 2175 (-3350 4050)(-2250 4050);
WIRE 3 2175 (-2250 4050)(-2250 3950);
WIRE 3 2175 (-3350 4050)(-3350 3950);
WIRE 3 2175 (-3350 3950)(-2250 3950);
WIRE 16 -1 (-175 3525)(-175 3625);
WIRE 16 -1 (150 3625)(-175 3625);
WIRE 16 -1 (-1075 3625)(-1025 3625);
FORCEPROP 0 LAST SIG_NAME A_HSC_MON
J 0
(-1035 3635);
DISPLAY 0.617021 (-1035 3635);
PAINT ORANGE (-1035 3635);
WIRE 16 -1 (-1025 3625)(-175 3625);
WIRE 16 -1 (-1025 3525)(-1025 3625);
WIRE 3 682 (75 2125)(75 1750);
WIRE 3 682 (-2825 2125)(75 2125);
WIRE 3 682 (-1100 1750)(75 1750);
WIRE 3 682 (-1100 1200)(-1100 1750);
WIRE 3 682 (-2825 2125)(-2825 1200);
WIRE 3 682 (-2825 1200)(-1100 1200);
WIRE 3 682 (-1200 0)(-1700 0);
WIRE 3 682 (-1200 -425)(-1200 0);
WIRE 3 682 (-1700 0)(-1700 50);
WIRE 3 682 (-1700 50)(-1750 50);
WIRE 3 682 (-1750 -425)(-1200 -425);
WIRE 3 682 (-1750 0)(-1750 -425);
WIRE 3 682 (-1350 500)(-1350 100);
WIRE 3 682 (-1750 50)(-1750 100);
WIRE 3 682 (-1750 100)(-1350 100);
WIRE 3 682 (-1750 500)(-1750 100);
WIRE 3 682 (-1750 500)(-1350 500);
WIRE 3 682 (-2000 0)(-1750 0);
WIRE 3 682 (-2000 550)(-2000 0);
WIRE 3 682 (-1750 500)(-1750 550);
WIRE 3 682 (-1750 550)(-2000 550);
WIRE 3 682 (-2400 400)(-2400 650);
WIRE 3 682 (-2025 400)(-2400 400);
WIRE 16 -1 (-1650 -50)(-1650 50);
WIRE 16 -1 (-1650 50)(-1650 150);
WIRE 16 -1 (-850 50)(-1650 50);
FORCEPROP 0 LAST SIG_NAME A_P12V_STBY_FP_TRIGGER
J 0
(-1622 72);
DISPLAY 0.617021 (-1622 72);
PAINT ORANGE (-1622 72);
FORCEPROP 2 LASTPROP $XR0 200 
J 0
(-1868 72);
DISPLAY 0.638298 (-1868 72);
PAINT MONO (-1868 72);
WIRE 16 -1 (-850 50)(-850 200);
WIRE 16 -1 (-850 200)(-700 200);
WIRE 16 -1 (-700 200)(-650 200);
WIRE 16 -1 (-700 -25)(-700 200);
WIRE 3 2175 (-1150 -325)(-350 -325);
WIRE 3 2175 (-350 375)(-350 -325);
WIRE 3 2175 (-1150 375)(-1150 -325);
WIRE 3 2175 (-1150 375)(-350 375);
WIRE 16 -1 (-50 350)(25 350);
WIRE 16 -1 (25 350)(25 -200);
WIRE 16 -1 (25 -200)(275 -200);
WIRE 16 -1 (275 -200)(350 -200);
WIRE 16 -1 (275 975)(275 -200);
FORCEPROP 0 LAST SIG_NAME A_P12V_STBY_FPH_GATE
R 1
J 0
(253 -178);
DISPLAY 0.617021 (253 -178);
PAINT ORANGE (253 -178);
FORCEPROP 2 LASTPROP $XRERR UNIQUE?
J 0
(13 -178);
DISPLAY 0.638298 (13 -178);
PAINT MONO (13 -178);
DISPLAY INVISIBLE (13 -178);
WIRE 16 -1 (1500 1025)(1500 675);
WIRE 16 -1 (2500 675)(1500 675);
FORCEPROP 0 LAST SIG_NAME FM_DISABLE_FAN_N
J 0
(1790 685);
DISPLAY 0.617021 (1790 685);
PAINT ORANGE (1790 685);
WIRE 16 -1 (1325 675)(1100 675);
WIRE 16 -1 (1500 675)(1325 675);
WIRE 16 -1 (1325 175)(1325 675);
WIRE 16 -1 (1150 175)(1325 175);
WIRE 16 -1 (-50 450)(600 450);
WIRE 16 -1 (600 450)(600 675);
WIRE 16 -1 (900 675)(600 675);
WIRE 16 -1 (600 675)(600 900);
WIRE 16 -1 (600 900)(2475 900);
FORCEPROP 0 LAST SIG_NAME FM_UV_ADR_TRIGGER_N
J 0
(1840 910);
DISPLAY 0.617021 (1840 910);
PAINT ORANGE (1840 910);
WIRE 16 -1 (600 1000)(600 900);
WIRE 68 -1 (-200 1200)(-200 600);
WIRE 68 -1 (-500 1200)(-200 1200);
WIRE 68 -1 (-500 1350)(-500 1200);
WIRE 16 -1 (-1050 250)(-1050 300);
WIRE 16 -1 (-1050 300)(-650 300);
WIRE 16 -1 (-1250 300)(-1050 300);
WIRE 16 -1 (-1250 600)(-1250 300);
WIRE 16 -1 (-1975 600)(-1975 475);
WIRE 16 -1 (-1975 700)(-1975 600);
WIRE 16 -1 (-1975 600)(-1250 600);
FORCEPROP 0 LAST SIG_NAME A_P12V_STBY_ADR_TRIGGER
J 0
(-1922 622);
DISPLAY 0.617021 (-1922 622);
PAINT ORANGE (-1922 622);
FORCEPROP 2 LASTPROP $XRERR UNIQUE?
J 0
(-2162 622);
DISPLAY 0.638298 (-2162 622);
PAINT MONO (-2162 622);
DISPLAY INVISIBLE (-2162 622);
WIRE 16 -1 (-3125 -150)(-2650 -150);
WIRE 16 -1 (-2650 -150)(-2650 300);
WIRE 16 -1 (-2600 300)(-2650 300);
FORCEPROP 2 LAST SIG_NAME FM_HSC_TIMER_EXP_N
J 0
(-3035 310);
DISPLAY 0.617021 (-3035 310);
PAINT ORANGE (-3035 310);
WIRE 16 -1 (-3300 300)(-2650 300);
WIRE 16 -1 (-3300 350)(-3300 300);
WIRE 3 682 (-2300 850)(-2300 1150);
WIRE 3 682 (-2000 850)(-2300 850);
WIRE 16 -1 (550 100)(550 175);
WIRE 16 -1 (550 175)(775 175);
WIRE 16 -1 (775 175)(950 175);
WIRE 16 -1 (775 -50)(775 175);
WIRE 16 -1 (775 -50)(1750 -50);
WIRE 16 -1 (2525 -50)(1750 -50);
FORCEPROP 0 LAST SIG_NAME IRQ_UV_DETECT_N
J 0
(1915 -40);
DISPLAY 0.617021 (1915 -40);
PAINT ORANGE (1915 -40);
WIRE 16 -1 (1750 125)(1750 -50);
WIRE 16 -1 (-675 1950)(-75 1950);
FORCEPROP 0 LAST SIG_NAME A_P12V_STBY_FP_TRIGGER
J 0
(-572 1972);
DISPLAY 0.617021 (-572 1972);
PAINT ORANGE (-572 1972);
FORCEPROP 2 LASTPROP $XR0 200 
J 0
(105 1950);
DISPLAY 0.638298 (105 1950);
PAINT MONO (105 1950);
WIRE 16 -1 (-1500 1950)(-1500 1875);
WIRE 16 -1 (-925 1950)(-1500 1950);
FORCEPROP 2 LAST SIG_NAME UV_HIGH_SET_N
J 0
(-1485 1960);
DISPLAY 0.680851 (-1485 1960);
PAINT ORANGE (-1485 1960);
FORCEPROP 2 LASTPROP $XRERR UNIQUE?
J 0
(-1725 1960);
DISPLAY 0.638298 (-1725 1960);
PAINT MONO (-1725 1960);
DISPLAY INVISIBLE (-1725 1960);
WIRE 16 -1 (-1650 2225)(-2750 2225);
WIRE 16 -1 (-1650 2225)(-1650 2250);
WIRE 16 -1 (-1650 2225)(-1025 2225);
FORCEPROP 0 LAST SIG_NAME FM_OC_DETECT_N
J 0
(-1360 2235);
DISPLAY 0.617021 (-1360 2235);
PAINT ORANGE (-1360 2235);
WIRE 16 -1 (1350 2625)(1350 2700);
WIRE 16 -1 (1475 2625)(1350 2625);
WIRE 16 -1 (1475 2625)(1475 2700);
WIRE 16 -1 (1475 2625)(1475 2250);
WIRE 16 -1 (375 2250)(500 2250);
FORCEPROP 0 LAST SIG_NAME A_HSC_HSN
J 0
(615 2260);
DISPLAY 0.617021 (615 2260);
PAINT ORANGE (615 2260);
WIRE 16 -1 (500 2250)(1475 2250);
WIRE 16 -1 (500 3625)(500 2250);
WIRE 16 -1 (350 3625)(500 3625);
WIRE 16 -1 (750 2625)(750 2700);
WIRE 16 -1 (875 2625)(750 2625);
WIRE 16 -1 (875 2625)(875 2700);
WIRE 16 -1 (875 2350)(875 2625);
WIRE 16 -1 (375 2350)(450 2350);
FORCEPROP 0 LAST SIG_NAME A_HSC_HSP
J 0
(615 2360);
DISPLAY 0.617021 (615 2360);
PAINT ORANGE (615 2360);
WIRE 16 -1 (450 2350)(875 2350);
WIRE 16 -1 (450 3150)(450 2350);
WIRE 16 -1 (325 3150)(450 3150);
WIRE 16 -1 (2325 3075)(2100 3075);
FORCEPROP 0 LAST SIG_NAME A_HSC_GATE1_R
J 0
(2090 3085);
DISPLAY 0.617021 (2090 3085);
PAINT ORANGE (2090 3085);
FORCEPROP 2 LASTPROP $XRERR UNIQUE?
J 0
(1850 3085);
DISPLAY 0.638298 (1850 3085);
PAINT MONO (1850 3085);
DISPLAY INVISIBLE (1850 3085);
WIRE 16 -1 (2325 3175)(2325 3075);
WIRE 16 -1 (-3950 -200)(-3725 -200);
WIRE 16 -1 (-3950 100)(-3950 -200);
WIRE 16 -1 (-3950 -375)(-3950 -200);
FORCEPROP 0 LAST SIG_NAME A_HSC_INAP
R 1
J 0
(-3960 -265);
DISPLAY 0.617021 (-3960 -265);
PAINT ORANGE (-3960 -265);
FORCEPROP 2 LASTPROP $XRERR UNIQUE?
J 0
(-4200 -265);
DISPLAY 0.638298 (-4200 -265);
PAINT MONO (-4200 -265);
DISPLAY INVISIBLE (-4200 -265);
WIRE 16 -1 (-4400 -300)(-4400 -125);
WIRE 16 -1 (-4400 150)(-4400 -125);
WIRE 16 -1 (-4150 -300)(-3725 -300);
WIRE 16 -1 (-4150 -125)(-4400 -125);
FORCEPROP 2 LAST SIG_NAME A_HSC_TIMER_R
J 0
(-4385 -115);
DISPLAY 0.617021 (-4385 -115);
PAINT ORANGE (-4385 -115);
FORCEPROP 2 LASTPROP $XRERR UNIQUE?
J 0
(-4625 -115);
DISPLAY 0.638298 (-4625 -115);
PAINT MONO (-4625 -115);
DISPLAY INVISIBLE (-4625 -115);
WIRE 16 -1 (-4150 -125)(-4150 -300);
WIRE 16 -1 (875 3200)(1025 3200);
FORCEPROP 0 LAST VOLTAGE +12V
J 0
(975 3250);
DISPLAY 1.021277 (975 3250);
PAINT SKYBLUE (975 3250);
DISPLAY INVISIBLE (975 3250);
WIRE 16 -1 (875 2900)(875 3200);
FORCEPROP 0 LAST SIG_NAME P12V_HSC_SENP1
R 1
J 0
(865 2885);
DISPLAY 0.617021 (865 2885);
PAINT ORANGE (865 2885);
FORCEPROP 2 LASTPROP $XRERR UNIQUE?
J 0
(625 2885);
DISPLAY 0.638298 (625 2885);
PAINT MONO (625 2885);
DISPLAY INVISIBLE (625 2885);
WIRE 16 -1 (2325 1775)(2050 1775);
WIRE 16 -1 (2325 1900)(2325 1775);
FORCEPROP 0 LAST SIG_NAME A_HSC_GATE3_R
J 0
(2065 1785);
DISPLAY 0.617021 (2065 1785);
PAINT ORANGE (2065 1785);
FORCEPROP 2 LASTPROP $XRERR UNIQUE?
J 0
(1825 1785);
DISPLAY 0.638298 (1825 1785);
PAINT MONO (1825 1785);
DISPLAY INVISIBLE (1825 1785);
WIRE 16 -1 (-4400 525)(-4650 525);
FORCEPROP 2 LAST SIG_NAME A_HSC_TIMER
J 0
(-4660 535);
DISPLAY 0.617021 (-4660 535);
PAINT ORANGE (-4660 535);
WIRE 16 -1 (-4400 350)(-4400 525);
WIRE 16 -1 (2350 2525)(2100 2525);
FORCEPROP 0 LAST SIG_NAME A_HSC_GATE2_R
J 0
(2090 2535);
DISPLAY 0.617021 (2090 2535);
PAINT ORANGE (2090 2535);
FORCEPROP 2 LASTPROP $XRERR UNIQUE?
J 0
(1850 2535);
DISPLAY 0.638298 (1850 2535);
PAINT MONO (1850 2535);
DISPLAY INVISIBLE (1850 2535);
WIRE 16 -1 (2350 2625)(2350 2525);
WIRE 16 -1 (-175 3325)(-175 3150);
WIRE 16 -1 (-175 3150)(125 3150);
WIRE 16 -1 (-1100 3150)(-675 3150);
FORCEPROP 0 LAST SIG_NAME A_HSC_MOP
J 0
(-1035 3110);
DISPLAY 0.617021 (-1035 3110);
PAINT ORANGE (-1035 3110);
WIRE 16 -1 (-675 3150)(-175 3150);
WIRE 16 -1 (-675 3100)(-675 3150);
WIRE 16 -1 (1350 3200)(1225 3200);
WIRE 16 -1 (1350 2900)(1350 3200);
FORCEPROP 0 LAST VOLTAGE +12V
J 0
(1400 2975);
DISPLAY 1.021277 (1400 2975);
PAINT SKYBLUE (1400 2975);
DISPLAY INVISIBLE (1400 2975);
FORCEPROP 0 LAST SIG_NAME P12V_HSC_SENN1
R 1
J 0
(1390 2910);
DISPLAY 0.617021 (1390 2910);
PAINT ORANGE (1390 2910);
FORCEPROP 2 LASTPROP $XRERR UNIQUE?
J 0
(1150 2910);
DISPLAY 0.638298 (1150 2910);
PAINT MONO (1150 2910);
DISPLAY INVISIBLE (1150 2910);
WIRE 16 -1 (-1700 1575)(-2300 1575);
FORCEPROP 2 LAST SIG_NAME UV_HIGH_SET
J 0
(-2310 1585);
DISPLAY 0.617021 (-2310 1585);
PAINT ORANGE (-2310 1585);
WIRE 3 682 (-1900 1650)(-1900 1500);
WIRE 3 682 (-1850 1650)(-1900 1650);
WIRE 3 682 (-1900 1500)(-1850 1500);
WIRE 3 682 (-1850 1500)(-1850 1650);
WIRE 16 -1 (750 3600)(1025 3600);
WIRE 16 -1 (750 2900)(750 3600);
FORCEPROP 0 LAST VOLTAGE +12V
J 0
(750 2950);
DISPLAY 1.021277 (750 2950);
PAINT SKYBLUE (750 2950);
DISPLAY INVISIBLE (750 2950);
FORCEPROP 0 LAST SIG_NAME P12V_HSC_SENP0
R 1
J 0
(740 2885);
DISPLAY 0.617021 (740 2885);
PAINT ORANGE (740 2885);
FORCEPROP 2 LASTPROP $XRERR UNIQUE?
J 0
(500 2885);
DISPLAY 0.638298 (500 2885);
PAINT MONO (500 2885);
DISPLAY INVISIBLE (500 2885);
WIRE 16 -1 (-3125 -50)(-2600 -50);
FORCEPROP 2 LAST SIG_NAME PWRGD_DSW_PWROK
J 0
(-3060 -40);
DISPLAY 0.617021 (-3060 -40);
PAINT ORANGE (-3060 -40);
WIRE 3 2175 (-1925 3950)(-1475 3950);
WIRE 3 2175 (-1475 3950)(-1475 3575);
WIRE 3 2175 (-1925 3950)(-1925 3575);
WIRE 3 2175 (-1925 3575)(-1475 3575);
WIRE 16 -1 (-2000 3800)(-1850 3800);
WIRE 16 -1 (-2000 3525)(-2000 3800);
FORCEPROP 0 LAST SIG_NAME A_HSC_LOW_DRAIN
R 1
J 0
(-2022 3522);
DISPLAY 0.617021 (-2022 3522);
PAINT ORANGE (-2022 3522);
FORCEPROP 2 LASTPROP $XRERR UNIQUE?
J 0
(-2262 3522);
DISPLAY 0.638298 (-2262 3522);
PAINT MONO (-2262 3522);
DISPLAY INVISIBLE (-2262 3522);
WIRE 16 -1 (1475 3600)(1225 3600);
WIRE 16 -1 (1475 2900)(1475 3600);
FORCEPROP 0 LAST VOLTAGE +12V
J 0
(1525 2975);
DISPLAY 1.021277 (1525 2975);
PAINT SKYBLUE (1525 2975);
DISPLAY INVISIBLE (1525 2975);
FORCEPROP 0 LAST SIG_NAME P12V_HSC_SENN0
R 1
J 0
(1515 2910);
DISPLAY 0.617021 (1515 2910);
PAINT ORANGE (1515 2910);
FORCEPROP 2 LASTPROP $XRERR UNIQUE?
J 0
(1275 2910);
DISPLAY 0.638298 (1275 2910);
PAINT MONO (1275 2910);
DISPLAY INVISIBLE (1275 2910);
WIRE 3 682 (1050 3725)(1050 3075);
WIRE 3 682 (1200 3725)(1050 3725);
WIRE 3 682 (1050 3075)(1200 3075);
WIRE 3 682 (1200 3075)(1200 3725);
WIRE 16 -1 (900 1875)(900 1775);
WIRE 16 -1 (1250 1875)(900 1875);
FORCEPROP 0 LAST SIG_NAME A_HSC_C
J 0
(915 1885);
DISPLAY 0.617021 (915 1885);
PAINT ORANGE (915 1885);
FORCEPROP 2 LASTPROP $XRERR UNIQUE?
J 0
(675 1885);
DISPLAY 0.638298 (675 1885);
PAINT MONO (675 1885);
DISPLAY INVISIBLE (675 1885);
WIRE 16 -1 (-4325 1200)(-3700 1200);
FORCEPROP 2 LAST SIG_NAME FM_OC_DETECT_EN_N
J 0
(-4260 1210);
DISPLAY 0.617021 (-4260 1210);
PAINT ORANGE (-4260 1210);
WIRE 16 -1 (-2800 4000)(-2300 4000);
WIRE 16 -1 (-2300 3225)(-2200 3225);
WIRE 16 -1 (-2300 4000)(-2300 3225);
WIRE 16 -1 (-2800 3225)(-2600 3225);
FORCEPROP 0 LAST SIG_NAME A_HSC_LOW_GATE
J 0
(-2722 3247);
DISPLAY 0.617021 (-2722 3247);
PAINT ORANGE (-2722 3247);
WIRE 16 -1 (-2600 3225)(-2300 3225);
WIRE 16 -1 (-2600 3450)(-2600 3225);
WIRE 16 -1 (1700 1775)(1850 1775);
WIRE 16 -1 (1450 1875)(1700 1875);
WIRE 16 -1 (1700 1875)(1700 1775);
WIRE 16 -1 (1700 2100)(1700 1875);
WIRE 16 -1 (1450 2100)(1700 2100);
FORCEPROP 0 LAST SIG_NAME A_HSC_GATE
J 0
(1440 2110);
DISPLAY 0.617021 (1440 2110);
PAINT ORANGE (1440 2110);
WIRE 16 -1 (1700 2100)(1700 2525);
WIRE 16 -1 (1900 2525)(1700 2525);
WIRE 16 -1 (1700 3075)(1700 2525);
WIRE 16 -1 (1900 3075)(1700 3075);
WIRE 16 -1 (-2900 2125)(-2900 1550);
WIRE 16 -1 (-3500 1550)(-3500 1650);
WIRE 16 -1 (-3500 1550)(-2900 1550);
FORCEPROP 0 LAST SIG_NAME FM_OC_DETECT_EN
J 0
(-3275 1560);
DISPLAY 0.617021 (-3275 1560);
PAINT ORANGE (-3275 1560);
FORCEPROP 2 LASTPROP $XRERR UNIQUE?
J 0
(-3515 1560);
DISPLAY 0.638298 (-3515 1560);
PAINT MONO (-3515 1560);
DISPLAY INVISIBLE (-3515 1560);
WIRE 16 -1 (-3500 1500)(-3500 1550);
WIRE 16 -1 (-3150 2600)(-1025 2600);
WIRE 16 -1 (-3150 2225)(-3150 2600);
FORCEPROP 0 LAST SIG_NAME IRQ_OC_DETECT_N
J 0
(-1622 2622);
DISPLAY 0.617021 (-1622 2622);
PAINT ORANGE (-1622 2622);
WIRE 16 -1 (-3050 2225)(-3150 2225);
WIRE 16 -1 (-3150 2225)(-3300 2225);
WIRE 16 -1 (-1650 3800)(-1550 3800);
WIRE 16 -1 (-1550 2700)(-1550 3800);
WIRE 16 -1 (-3300 2700)(-3300 2225);
WIRE 16 -1 (-3300 2700)(-2500 2700);
WIRE 16 -1 (-2500 2700)(-1550 2700);
WIRE 16 -1 (-2500 3125)(-2500 2700);
WIRE 16 -1 (-2800 3125)(-2750 3125);
WIRE 16 -1 (-2750 3125)(-2500 3125);
WIRE 16 -1 (-2750 3350)(-2750 3125);
WIRE 16 -1 (-2950 3350)(-2750 3350);
WIRE 16 -1 (-2950 3450)(-2950 3350);
WIRE 16 -1 (-4575 3675)(-4625 3675);
FORCEPROP 0 LAST SIG_NAME A_HSC_CSOUT
J 0
(-4597 3697);
DISPLAY 0.617021 (-4597 3697);
PAINT ORANGE (-4597 3697);
WIRE 16 -1 (-4575 3550)(-4575 3675);
WIRE 16 -1 (-4150 2925)(-4150 3675);
WIRE 16 -1 (-4150 3675)(-4575 3675);
WIRE 16 -1 (-4150 2625)(-4150 2550);
WIRE 16 -1 (-4150 2725)(-4150 2625);
WIRE 16 -1 (-3800 2975)(-3400 2975);
WIRE 16 -1 (-3800 2625)(-4150 2625);
WIRE 16 -1 (-3800 2625)(-3800 2975);
FORCEPROP 0 LAST SIG_NAME A_HSC_HIGH
J 0
(-3797 2972);
DISPLAY 0.617021 (-3797 2972);
PAINT ORANGE (-3797 2972);
FORCEPROP 2 LASTPROP $XRERR UNIQUE?
J 0
(-4037 2972);
DISPLAY 0.638298 (-4037 2972);
PAINT MONO (-4037 2972);
DISPLAY INVISIBLE (-4037 2972);
DOT 1 (-1650 50);
DOT 1 (600 900);
DOT 1 (1325 675);
DOT 1 (-1750 100);
DOT 1 (-1975 600);
DOT 1 (-3150 2225);
DOT 1 (600 675);
DOT 1 (275 -200);
DOT 1 (-3500 1550);
DOT 1 (-1125 1000);
DOT 1 (-4575 3675);
DOT 1 (-3800 3600);
DOT 1 (-2300 3225);
DOT 1 (-2600 3750);
DOT 1 (-1050 300);
DOT 1 (-3450 675);
DOT 1 (-3300 675);
DOT 1 (-4400 -125);
DOT 1 (-3950 -200);
DOT 1 (-2650 300);
DOT 1 (-2750 3125);
DOT 1 (-2600 3225);
DOT 1 (-1025 3625);
DOT 1 (-675 3150);
DOT 1 (-175 3150);
DOT 1 (-175 3625);
DOT 1 (775 175);
DOT 1 (1500 675);
DOT 1 (1700 1875);
DOT 1 (500 2250);
DOT 1 (450 2350);
DOT 1 (900 3250);
DOT 1 (900 3650);
DOT 1 (1700 2100);
DOT 1 (1700 2525);
DOT 1 (2525 2100);
DOT 1 (2525 2150);
DOT 1 (2525 2775);
DOT 1 (2525 2825);
DOT 1 (2525 2875);
DOT 1 (2525 3325);
DOT 1 (2525 3375);
DOT 1 (2525 3425);
DOT 1 (2525 3700);
DOT 1 (-2500 2700);
DOT 1 (-1650 2225);
DOT 1 (1750 -50);
DOT 1 (1775 3325);
DOT 1 (1775 2775);
DOT 1 (1475 2625);
DOT 1 (1300 3325);
DOT 1 (875 2625);
DOT 1 (1300 3550);
DOT 1 (1300 3250);
DOT 1 (-1750 500);
DOT 1 (900 3550);
DOT 1 (-4150 2625);
DOT 1 (-4575 3075);
DOT 1 (-1975 1000);
DOT 1 (-700 200);
FORCENOTE
IOUT FAST PROCHOT CIRCUIT
(-4945 3825) 0;
DISPLAY LEFT (-4945 3825);
DISPLAY 1.595745 (-4945 3825);
PAINT PURPLE (-4945 3825);
FORCENOTE
INAP (LOW OC): 40.6A
(-4950 1800) 0;
DISPLAY LEFT (-4950 1800);
DISPLAY 0.808511 (-4950 1800);
PAINT PURPLE (-4950 1800);
FORCENOTE
TP FAB3-DVT CHANGE R9P9 FROM 10K TO 3.74K 20161208
(-3100 675) 0;
DISPLAY LEFT (-3100 675);
DISPLAY 0.638298 (-3100 675);
PAINT RED (-3100 675);
FORCENOTE
TP FAB1 MOVE R6W1 AND R6W2 TO PAGE 137 0308
(-2800 1400) 0;
DISPLAY LEFT (-2800 1400);
DISPLAY 1.021277 (-2800 1400);
PAINT RED (-2800 1400);
FORCENOTE
TP FAB3-DVT CHANGE R9P7 FROM 249K TO 100K 20161208
(-2400 1150) 0;
DISPLAY LEFT (-2400 1150);
DISPLAY 0.638298 (-2400 1150);
PAINT RED (-2400 1150);
FORCENOTE
LOW VOLTAGE TIGGER CIRCUIT: ADR TRIGGGER
(-1870 1025) 0;
DISPLAY LEFT (-1870 1025);
DISPLAY 1.021277 (-1870 1025);
PAINT VIOLET (-1870 1025);
FORCENOTE
TRIP: 10.9V
(-1720 825) 0;
DISPLAY LEFT (-1720 825);
DISPLAY 1.595745 (-1720 825);
PAINT PURPLE (-1720 825);
FORCENOTE
TP FAB1 R9P13 NEED TO CHANGE TO 270K OHM
(-1525 500) 0;
DISPLAY LEFT (-1525 500);
DISPLAY 0.680851 (-1525 500);
PAINT RED (-1525 500);
FORCENOTE
TP FAB1 CHANGE RES 0422
(-2225 -350) 0;
DISPLAY LEFT (-2225 -350);
DISPLAY 0.638298 (-2225 -350);
PAINT RED (-2225 -350);
FORCENOTE
8.3V (7.989V~8.578V) NOMINAL ON P12V_STBY FAILING
(-3575 -675) 0;
DISPLAY LEFT (-3575 -675);
DISPLAY 1.021277 (-3575 -675);
PAINT PURPLE (-3575 -675);
FORCENOTE
UV_HIGH_SET=0: TRIP = 11V (10.721V~11.319V)
(-1050 1400) 0;
DISPLAY LEFT (-1050 1400);
DISPLAY 0.808511 (-1050 1400);
PAINT PURPLE (-1050 1400);
FORCENOTE
LOW VOLTAGE TIGGER CIRCUIT: FAST PROCHOT
(-1520 -525) 0;
DISPLAY LEFT (-1520 -525);
DISPLAY 1.595745 (-1520 -525);
PAINT PURPLE (-1520 -525);
FORCENOTE
DSW_PWROK FIRST TRIP POINT
(-3575 -600) 0;
DISPLAY LEFT (-3575 -600);
DISPLAY 1.021277 (-3575 -600);
PAINT PURPLE (-3575 -600);
FORCENOTE
TP FAB3 NOPOP CR9P1 1021
(925 -25) 0;
DISPLAY LEFT (925 -25);
DISPLAY 0.638298 (925 -25);
PAINT RED (925 -25);
FORCENOTE
TP FAB1 ADD ATTRIBUTES 0307
(1275 3700) 0;
DISPLAY LEFT (1275 3700);
DISPLAY 0.808511 (1275 3700);
PAINT RED (1275 3700);
FORCENOTE
TP FAB1 CONNECT FROM HOT SWAP 1231
(-4650 4000) 0;
DISPLAY LEFT (-4650 4000);
DISPLAY 1.021277 (-4650 4000);
PAINT RED (-4650 4000);
FORCENOTE
INBN (HIGH OC): 47.9A (DEFAULT)
(-4950 1725) 0;
DISPLAY LEFT (-4950 1725);
DISPLAY 0.808511 (-4950 1725);
PAINT PURPLE (-4950 1725);
FORCENOTE
SINGLE SIDE:
(-4945 1875) 0;
DISPLAY LEFT (-4945 1875);
DISPLAY 0.808511 (-4945 1875);
PAINT PURPLE (-4945 1875);
FORCENOTE
TP FAB1 CHANGE RES 0422
(-4975 2100) 0;
DISPLAY LEFT (-4975 2100);
DISPLAY 0.638298 (-4975 2100);
PAINT RED (-4975 2100);
FORCENOTE
TP FAB3 CHANGE R1D20 AND R1D14 RES FOR DOUBLE SIDE 1006
(-4975 2050) 0;
DISPLAY LEFT (-4975 2050);
DISPLAY 0.638298 (-4975 2050);
PAINT RED (-4975 2050);
FORCENOTE
INAP (LOW OC): 70A (DEFAULT)
(-4950 1575) 0;
DISPLAY LEFT (-4950 1575);
DISPLAY 0.808511 (-4950 1575);
PAINT PURPLE (-4950 1575);
FORCENOTE
U1D2
(-4950 1950) 0;
DISPLAY LEFT (-4950 1950);
DISPLAY 1.021277 (-4950 1950);
PAINT PURPLE (-4950 1950);
FORCENOTE
DOUBLE SIDE:
(-4950 1650) 0;
DISPLAY LEFT (-4950 1650);
DISPLAY 0.808511 (-4950 1650);
PAINT PURPLE (-4950 1650);
FORCENOTE
INBN (HIGH OC): 77.3A 
(-4950 1500) 0;
DISPLAY LEFT (-4950 1500);
DISPLAY 0.808511 (-4950 1500);
PAINT PURPLE (-4950 1500);
FORCENOTE
TP FAB1 ADD UV FPH VOLTAGE THRESHOLD SELECTION 1117
(-2800 2050) 0;
DISPLAY LEFT (-2800 2050);
DISPLAY 1.021277 (-2800 2050);
PAINT RED (-2800 2050);
FORCENOTE
TP FAB1 R6W3 CHANGE TO 232K 1119
(-1225 1775) 0;
DISPLAY LEFT (-1225 1775);
DISPLAY 1.021277 (-1225 1775);
PAINT RED (-1225 1775);
FORCENOTE
TRIP = 10.218V (9.832V~10.561V)
(-1050 1550) 0;
DISPLAY LEFT (-1050 1550);
DISPLAY 0.808511 (-1050 1550);
PAINT PURPLE (-1050 1550);
FORCENOTE
U9P1:
(-1050 1650) 0;
DISPLAY LEFT (-1050 1650);
DISPLAY 1.021277 (-1050 1650);
PAINT PURPLE (-1050 1650);
FORCENOTE
INAP (ADR LOW VOLTAGE)
(-1050 1600) 0;
DISPLAY LEFT (-1050 1600);
DISPLAY 0.808511 (-1050 1600);
PAINT PURPLE (-1050 1600);
FORCENOTE
INBN (FPH LOW VOLTAGE)
(-1050 1500) 0;
DISPLAY LEFT (-1050 1500);
DISPLAY 0.808511 (-1050 1500);
PAINT PURPLE (-1050 1500);
FORCENOTE
NOTE: GATE VOLTAGE: 24V PK
(1230 1575) 0;
DISPLAY LEFT (1230 1575);
DISPLAY 0.808511 (1230 1575);
PAINT PURPLE (1230 1575);
FORCENOTE
ROOM: HOT_SWAP
(-4895 1300) 0;
DISPLAY LEFT (-4895 1300);
DISPLAY 1.021277 (-4895 1300);
PAINT PURPLE (-4895 1300);
FORCENOTE
HSC TIMER
(-4595 825) 0;
DISPLAY LEFT (-4595 825);
DISPLAY 2.000000 (-4595 825);
PAINT PURPLE (-4595 825);
FORCENOTE
OCP LOW TRIP: 41.4A
(-2200 4000) 0;
DISPLAY LEFT (-2200 4000);
DISPLAY 0.808511 (-2200 4000);
PAINT PURPLE (-2200 4000);
FORCENOTE
TP FAB1 POP 0 OHM 1231
(-1600 4000) 0;
DISPLAY LEFT (-1600 4000);
DISPLAY 1.021277 (-1600 4000);
PAINT RED (-1600 4000);
FORCENOTE
P12V_STBY (12V  STBY TO  THE BOARD)
(1570 4012) 0;
DISPLAY LEFT (1570 4012);
DISPLAY 0.808511 (1570 4012);
PAINT PURPLE (1570 4012);
FORCENOTE
P12V_PSU (12V INPUT POWER  FROM EXTERNAL PSU)
(95 3937) 0;
DISPLAY LEFT (95 3937);
DISPLAY 0.808511 (95 3937);
PAINT PURPLE (95 3937);
FORCENOTE
TP FAB1 ADD CAP 1117
(-1150 -400) 0;
DISPLAY LEFT (-1150 -400);
DISPLAY 1.021277 (-1150 -400);
PAINT RED (-1150 -400);
FORCENOTE
UV_HIGH_SET=1: TRIP = 11.5V (11.158V~11.789V) (DEFAULT)
(-1050 1450) 0;
DISPLAY LEFT (-1050 1450);
DISPLAY 0.808511 (-1050 1450);
PAINT PURPLE (-1050 1450);
QUIT
